FILE_TYPE = MACRO_DRAWING;
SET COLOR_WIRE YELLOW;
SET COLOR_PROP ORANGE;
SET COLOR_DOT WHITE;
SET COLOR_ARC YELLOW;
SET COLOR_BODY GREEN;
SET COLOR_NOTE PURPLE;
SET PROP_DISPLAY VALUE;
SET PAGE_NUMBER P363;
FORCEADD UNIVERSAL_POWER..1
(-2875 475);
FORCEPROP 3 LASTPIN (-2875 425) SIG_NAME P12V_PSU\g
J 0
(-2865 435);
DISPLAY 0.659574 (-2865 435);
PAINT MONO (-2865 435);
DISPLAY INVISIBLE (-2865 435);
FORCEPROP 1 LAST HDL_POWER P12V_PSU
J 1
(-2875 525);
DISPLAY 0.872340 (-2875 525);
PAINT GREEN (-2875 525);
FORCEPROP 2 LAST CDS_LIB pure_quanta_power
J 0
(-2875 475);
DISPLAY INVISIBLE (-2875 475);
FORCEPROP 1 LAST PATH I369
J 0
(-2825 500);
DISPLAY 0.872340 (-2825 500);
PAINT AQUA (-2825 500);
DISPLAY INVISIBLE (-2825 500);
FORCEADD UNIVERSAL_GND..1
(-4375 -1200);
FORCEPROP 3 LASTPIN (-4375 -1150) SIG_NAME GND\g
J 0
(-4365 -1140);
DISPLAY 0.659574 (-4365 -1140);
PAINT MONO (-4365 -1140);
DISPLAY INVISIBLE (-4365 -1140);
FORCEPROP 2 LAST CDS_LIB pure_quanta_power
J 0
(-4375 -1200);
DISPLAY INVISIBLE (-4375 -1200);
FORCEPROP 1 LAST HDL_POWER GND
J 1
(-4350 -1275);
DISPLAY 0.872340 (-4350 -1275);
PAINT GREEN (-4350 -1275);
DISPLAY INVISIBLE (-4350 -1275);
FORCEPROP 1 LAST PATH I370
J 0
(-4300 -1200);
DISPLAY 0.872340 (-4300 -1200);
PAINT AQUA (-4300 -1200);
DISPLAY INVISIBLE (-4300 -1200);
FORCEADD OFFPAGE..1
(-7050 675);
FORCEPROP 2 LAST $XR5 253 
J 0
(-7901 675);
DISPLAY 0.638298 (-7901 675);
PAINT MONO (-7901 675);
FORCEPROP 2 LAST $XR4 251 
J 0
(-7781 675);
DISPLAY 0.638298 (-7781 675);
PAINT MONO (-7781 675);
FORCEPROP 2 LAST $XR3 246 
J 0
(-7661 675);
DISPLAY 0.638298 (-7661 675);
PAINT MONO (-7661 675);
FORCEPROP 2 LAST $XR2 139 
J 0
(-7541 675);
DISPLAY 0.638298 (-7541 675);
PAINT MONO (-7541 675);
FORCEPROP 2 LAST $XR1 132 
J 0
(-7421 675);
DISPLAY 0.638298 (-7421 675);
PAINT MONO (-7421 675);
FORCEPROP 2 LAST $XR0 80 
J 0
(-7301 675);
DISPLAY 0.638298 (-7301 675);
PAINT MONO (-7301 675);
FORCEPROP 2 LAST CDS_LIB standard
J 0
(-7050 675);
DISPLAY INVISIBLE (-7050 675);
FORCEPROP 1 LAST OFFPAGE TRUE
J 0
(-6725 550);
DISPLAY 0.872340 (-6725 550);
DISPLAY INVISIBLE (-6725 550);
FORCEPROP 1 LAST COMMENT_BODY TRUE
J 0
(-6925 575);
DISPLAY 0.872340 (-6925 575);
PAINT GREEN (-6925 575);
DISPLAY INVISIBLE (-6925 575);
FORCEPROP 2 LAST PATH I371
J 0
(-7350 725);
DISPLAY 1.021277 (-7350 725);
DISPLAY INVISIBLE (-7350 725);
FORCEADD OFFPAGE..4
(-875 675);
FORCEPROP 2 LAST $XR0 80 
J 0
(-689 675);
DISPLAY 0.638298 (-689 675);
PAINT MONO (-689 675);
FORCEPROP 2 LAST CDS_LIB standard
J 0
(-875 675);
DISPLAY INVISIBLE (-875 675);
FORCEPROP 1 LAST OFFPAGE TRUE
J 0
(-550 550);
DISPLAY 0.872340 (-550 550);
PAINT GREEN (-550 550);
DISPLAY INVISIBLE (-550 550);
FORCEPROP 1 LAST COMMENT_BODY TRUE
J 0
(-900 575);
DISPLAY 0.872340 (-900 575);
PAINT PEACH (-900 575);
DISPLAY INVISIBLE (-900 575);
FORCEPROP 2 LAST PATH I377
J 0
(-500 725);
DISPLAY 1.021277 (-500 725);
DISPLAY INVISIBLE (-500 725);
FORCEADD OFFPAGE..4
(-875 625);
FORCEPROP 2 LAST $XR0 242 
J 0
(-689 625);
DISPLAY 0.638298 (-689 625);
PAINT MONO (-689 625);
FORCEPROP 2 LAST CDS_LIB standard
J 0
(-875 625);
DISPLAY INVISIBLE (-875 625);
FORCEPROP 1 LAST OFFPAGE TRUE
J 0
(-550 500);
DISPLAY 0.872340 (-550 500);
PAINT GREEN (-550 500);
DISPLAY INVISIBLE (-550 500);
FORCEPROP 1 LAST COMMENT_BODY TRUE
J 0
(-900 525);
DISPLAY 0.872340 (-900 525);
PAINT PEACH (-900 525);
DISPLAY INVISIBLE (-900 525);
FORCEPROP 2 LAST PATH I378
J 0
(-500 675);
DISPLAY 1.021277 (-500 675);
DISPLAY INVISIBLE (-500 675);
FORCEADD OFFPAGE..3
(-900 775);
FORCEPROP 2 LAST $XR0 241 
J 0
(-686 775);
DISPLAY 0.638298 (-686 775);
PAINT MONO (-686 775);
FORCEPROP 2 LAST CDS_LIB standard
J 0
(-900 775);
DISPLAY INVISIBLE (-900 775);
FORCEPROP 1 LAST OFFPAGE TRUE
J 0
(-575 650);
DISPLAY 0.872340 (-575 650);
PAINT GREEN (-575 650);
DISPLAY INVISIBLE (-575 650);
FORCEPROP 1 LAST COMMENT_BODY TRUE
J 0
(-950 675);
DISPLAY 0.872340 (-950 675);
PAINT GREEN (-950 675);
DISPLAY INVISIBLE (-950 675);
FORCEPROP 2 LAST PATH I379
J 0
(-175 825);
DISPLAY 1.021277 (-175 825);
DISPLAY INVISIBLE (-175 825);
FORCEADD OFFPAGE..4
(-900 825);
FORCEPROP 2 LAST $XR0 241 
J 0
(-714 825);
DISPLAY 0.638298 (-714 825);
PAINT MONO (-714 825);
FORCEPROP 2 LAST CDS_LIB standard
J 0
(-900 825);
DISPLAY INVISIBLE (-900 825);
FORCEPROP 1 LAST OFFPAGE TRUE
J 0
(-575 700);
DISPLAY 0.872340 (-575 700);
PAINT GREEN (-575 700);
DISPLAY INVISIBLE (-575 700);
FORCEPROP 1 LAST COMMENT_BODY TRUE
J 0
(-925 725);
DISPLAY 0.872340 (-925 725);
PAINT PEACH (-925 725);
DISPLAY INVISIBLE (-925 725);
FORCEPROP 2 LAST PATH I380
J 0
(-75 875);
DISPLAY 1.021277 (-75 875);
DISPLAY INVISIBLE (-75 875);
FORCEADD Q_RES..1
(-2150 725);
FORCEPROP 1 LAST LOCATION R2802
J 0
(-2375 725);
DISPLAY 0.638298 (-2375 725);
FORCEPROP 2 LAST $SEC 1
J 0
(-2200 925);
DISPLAY 0.680851 (-2200 925);
PAINT MONO (-2200 925);
DISPLAY INVISIBLE (-2200 925);
FORCEPROP 2 LAST CDS_SEC 1
J 0
(-2200 925);
DISPLAY 1.021277 (-2200 925);
DISPLAY INVISIBLE (-2200 925);
FORCEPROP 1 LASTPIN (-2250 725) $PN 1
J 0
(-2238 737);
DISPLAY 0.787234 (-2238 737);
FORCEPROP 1 LASTPIN (-2050 725) $PN 2
J 0
(-2088 737);
DISPLAY 0.787234 (-2088 737);
FORCEPROP 1 LAST MATERIAL CHIP
J 0
(-1850 725);
DISPLAY 0.404255 (-1850 725);
FORCEPROP 1 LAST VALUE 0
J 2
(-1975 725);
DISPLAY 0.404255 (-1975 725);
FORCEPROP 1 LAST TOLERANCE 5%
J 0
(-1925 725);
DISPLAY 0.404255 (-1925 725);
FORCEPROP 2 LAST CDS_LIB pure_quanta
J 0
(-2150 725);
PAINT MONO (-2150 725);
DISPLAY INVISIBLE (-2150 725);
FORCEPROP 1 LAST PACK_TYPE 0402LF
J 0
(-1900 725);
DISPLAY 0.638298 (-1900 725);
DISPLAY INVISIBLE (-1900 725);
FORCEPROP 1 LAST WATTAGE 1/16W
J 2
(-2175 575);
DISPLAY 0.978723 (-2175 575);
DISPLAY INVISIBLE (-2175 575);
FORCEPROP 1 LAST PATH I387
J 0
(-2200 875);
DISPLAY 0.978723 (-2200 875);
PAINT WHITE (-2200 875);
DISPLAY INVISIBLE (-2200 875);
FORCEPROP 1 LAST PART_NUMBER CS00002JB13
J 0
(-2275 575);
DISPLAY 0.510638 (-2275 575);
DISPLAY INVISIBLE (-2275 575);
FORCEPROP 1 LAST LOCATION R2802
J 0
(-2200 925);
DISPLAY 1.021277 (-2200 925);
DISPLAY INVISIBLE (-2200 925);
FORCEADD Q_RES..1
(-2150 675);
FORCEPROP 1 LAST LOCATION R2803
J 0
(-2375 675);
DISPLAY 0.638298 (-2375 675);
FORCEPROP 2 LAST $SEC 1
J 0
(-2200 875);
DISPLAY 0.680851 (-2200 875);
PAINT MONO (-2200 875);
DISPLAY INVISIBLE (-2200 875);
FORCEPROP 2 LAST CDS_SEC 1
J 0
(-2200 875);
DISPLAY 1.021277 (-2200 875);
DISPLAY INVISIBLE (-2200 875);
FORCEPROP 1 LASTPIN (-2250 675) $PN 1
J 0
(-2238 687);
DISPLAY 0.787234 (-2238 687);
FORCEPROP 1 LASTPIN (-2050 675) $PN 2
J 0
(-2088 687);
DISPLAY 0.787234 (-2088 687);
FORCEPROP 1 LAST VALUE 0
J 2
(-1975 675);
DISPLAY 0.404255 (-1975 675);
FORCEPROP 1 LAST TOLERANCE 5%
J 0
(-1925 675);
DISPLAY 0.404255 (-1925 675);
FORCEPROP 1 LAST MATERIAL CHIP
J 0
(-1850 675);
DISPLAY 0.404255 (-1850 675);
FORCEPROP 2 LAST CDS_LIB pure_quanta
J 0
(-2150 675);
PAINT MONO (-2150 675);
DISPLAY INVISIBLE (-2150 675);
FORCEPROP 1 LAST WATTAGE 1/16W
J 2
(-2175 525);
DISPLAY 0.978723 (-2175 525);
DISPLAY INVISIBLE (-2175 525);
FORCEPROP 1 LAST PACK_TYPE 0402LF
J 0
(-1900 675);
DISPLAY 0.638298 (-1900 675);
DISPLAY INVISIBLE (-1900 675);
FORCEPROP 1 LAST PATH I388
J 0
(-2200 825);
DISPLAY 0.978723 (-2200 825);
PAINT WHITE (-2200 825);
DISPLAY INVISIBLE (-2200 825);
FORCEPROP 1 LAST PART_NUMBER CS00002JB13
J 0
(-2275 525);
DISPLAY 0.510638 (-2275 525);
DISPLAY INVISIBLE (-2275 525);
FORCEPROP 1 LAST LOCATION R2803
J 0
(-2200 875);
DISPLAY 1.021277 (-2200 875);
DISPLAY INVISIBLE (-2200 875);
FORCEADD MOSFET_NCH_GDS_ESD_PROTECTED..1
(-6000 -2650);
FORCEPROP 1 LAST LOCATION U190
J 0
(-5858 -2686);
DISPLAY 0.723404 (-5858 -2686);
PAINT GREEN (-5858 -2686);
FORCEPROP 0 LAST $SEC 1
J 0
(-5850 -2550);
DISPLAY 0.680851 (-5850 -2550);
PAINT MONO (-5850 -2550);
DISPLAY INVISIBLE (-5850 -2550);
FORCEPROP 2 LAST CDS_SEC 1
J 0
(-5850 -2550);
DISPLAY 1.021277 (-5850 -2550);
DISPLAY INVISIBLE (-5850 -2550);
FORCEPROP 0 LASTPIN (-5975 -2450) $PN D
R 1
J 0
(-5985 -2440);
DISPLAY 0.680851 (-5985 -2440);
PAINT MONO (-5985 -2440);
FORCEPROP 0 LASTPIN (-6175 -2650) $PN G
J 2
(-6185 -2640);
DISPLAY 0.680851 (-6185 -2640);
PAINT MONO (-6185 -2640);
FORCEPROP 0 LASTPIN (-5975 -2850) $PN S
R 1
J 2
(-5985 -2860);
DISPLAY 0.680851 (-5985 -2860);
PAINT MONO (-5985 -2860);
FORCEPROP 2 LAST PART_TYPE SMLF
J 0
(-5850 -2600);
DISPLAY 1.021277 (-5850 -2600);
FORCEPROP 1 LAST MATERIAL IC
J 0
(-5858 -2795);
DISPLAY 0.723404 (-5858 -2795);
PAINT GREEN (-5858 -2795);
FORCEPROP 2 LAST VALUE 2N7002K
J 0
(-5850 -2650);
DISPLAY 1.021277 (-5850 -2650);
FORCEPROP 2 LAST CDS_LIB pure_quanta
J 0
(-6000 -2650);
DISPLAY INVISIBLE (-6000 -2650);
FORCEPROP 1 LAST NEEDS_NO_SIZE TRUE
J 0
(-5875 -2760);
DISPLAY 0.723404 (-5875 -2760);
PAINT GREEN (-5875 -2760);
DISPLAY INVISIBLE (-5875 -2760);
FORCEPROP 1 LAST CDS_LMAN_SYM_OUTLINE -125,150,125,-150
J 0
(-6000 -2650);
DISPLAY 0.468085 (-6000 -2650);
PAINT GREEN (-6000 -2650);
DISPLAY INVISIBLE (-6000 -2650);
FORCEPROP 1 LAST PATH I392
J 0
(-5875 -2800);
DISPLAY 0.723404 (-5875 -2800);
PAINT GREEN (-5875 -2800);
DISPLAY INVISIBLE (-5875 -2800);
FORCEPROP 1 LAST PART_NUMBER BAM70020002
J 0
(-5858 -2738);
DISPLAY 0.723404 (-5858 -2738);
PAINT GREEN (-5858 -2738);
DISPLAY INVISIBLE (-5858 -2738);
FORCEADD OFFPAGE..1
(-7850 -2650);
FORCEPROP 2 LAST $XR0 82 
J 0
(-8101 -2650);
DISPLAY 0.638298 (-8101 -2650);
PAINT MONO (-8101 -2650);
FORCEPROP 2 LAST CDS_LIB standard
J 0
(-7850 -2650);
DISPLAY INVISIBLE (-7850 -2650);
FORCEPROP 1 LAST OFFPAGE TRUE
J 0
(-7525 -2775);
DISPLAY 0.872340 (-7525 -2775);
DISPLAY INVISIBLE (-7525 -2775);
FORCEPROP 1 LAST COMMENT_BODY TRUE
J 0
(-7725 -2750);
DISPLAY 0.872340 (-7725 -2750);
PAINT GREEN (-7725 -2750);
DISPLAY INVISIBLE (-7725 -2750);
FORCEPROP 2 LAST PATH I393
J 0
(-8150 -2600);
DISPLAY 1.021277 (-8150 -2600);
DISPLAY INVISIBLE (-8150 -2600);
FORCEADD Q_RES..1
(-6875 -2650);
FORCEPROP 1 LAST LOCATION R2793
J 0
(-7100 -2650);
DISPLAY 0.638298 (-7100 -2650);
FORCEPROP 2 LAST $SEC 1
J 0
(-6925 -2450);
DISPLAY 0.680851 (-6925 -2450);
PAINT MONO (-6925 -2450);
DISPLAY INVISIBLE (-6925 -2450);
FORCEPROP 2 LAST CDS_SEC 1
J 0
(-6925 -2450);
DISPLAY 1.021277 (-6925 -2450);
DISPLAY INVISIBLE (-6925 -2450);
FORCEPROP 1 LASTPIN (-6975 -2650) $PN 1
J 0
(-6963 -2638);
DISPLAY 0.787234 (-6963 -2638);
FORCEPROP 1 LASTPIN (-6775 -2650) $PN 2
J 0
(-6813 -2638);
DISPLAY 0.787234 (-6813 -2638);
FORCEPROP 1 LAST MATERIAL CHIP
J 0
(-7100 -2725);
DISPLAY 0.404255 (-7100 -2725);
FORCEPROP 1 LAST VALUE 0
J 2
(-7075 -2675);
DISPLAY 0.404255 (-7075 -2675);
FORCEPROP 1 LAST TOLERANCE 5%
J 0
(-7100 -2700);
DISPLAY 0.404255 (-7100 -2700);
FORCEPROP 1 LAST PACK_TYPE 0402LF
J 0
(-6625 -2650);
DISPLAY 0.510638 (-6625 -2650);
DISPLAY INVISIBLE (-6625 -2650);
FORCEPROP 1 LAST WATTAGE 1/16W
J 2
(-6900 -2800);
DISPLAY 0.978723 (-6900 -2800);
DISPLAY INVISIBLE (-6900 -2800);
FORCEPROP 2 LAST CDS_LIB pure_quanta
J 0
(-6875 -2650);
PAINT MONO (-6875 -2650);
DISPLAY INVISIBLE (-6875 -2650);
FORCEPROP 1 LAST PATH I394
J 0
(-6925 -2500);
DISPLAY 0.978723 (-6925 -2500);
PAINT WHITE (-6925 -2500);
DISPLAY INVISIBLE (-6925 -2500);
FORCEPROP 1 LAST PART_NUMBER CS00002JB13
J 0
(-7000 -2800);
DISPLAY 0.510638 (-7000 -2800);
DISPLAY INVISIBLE (-7000 -2800);
FORCEPROP 1 LAST LOCATION R2793
J 0
(-6925 -2450);
DISPLAY 1.021277 (-6925 -2450);
DISPLAY INVISIBLE (-6925 -2450);
FORCEADD UNIVERSAL_POWER..1
(-5975 -1775);
FORCEPROP 3 LASTPIN (-5975 -1825) SIG_NAME P3V3_AUX\g
J 0
(-5965 -1815);
DISPLAY 0.659574 (-5965 -1815);
PAINT MONO (-5965 -1815);
DISPLAY INVISIBLE (-5965 -1815);
FORCEPROP 1 LAST HDL_POWER P3V3_AUX
J 1
(-5975 -1725);
DISPLAY 0.872340 (-5975 -1725);
PAINT GREEN (-5975 -1725);
FORCEPROP 2 LAST CDS_LIB pure_quanta_power
J 0
(-5975 -1775);
DISPLAY INVISIBLE (-5975 -1775);
FORCEPROP 1 LAST PATH I395
J 0
(-5925 -1750);
DISPLAY 0.872340 (-5925 -1750);
PAINT AQUA (-5925 -1750);
DISPLAY INVISIBLE (-5925 -1750);
FORCEADD Q_RES..2
(-5975 -2050);
FORCEPROP 1 LAST LOCATION R2794
J 0
(-5930 -1925);
DISPLAY 0.787234 (-5930 -1925);
FORCEPROP 2 LAST $SEC 1
J 0
(-5925 -1825);
DISPLAY 0.680851 (-5925 -1825);
PAINT MONO (-5925 -1825);
DISPLAY INVISIBLE (-5925 -1825);
FORCEPROP 2 LAST CDS_SEC 1
J 0
(-5925 -1825);
DISPLAY 1.021277 (-5925 -1825);
DISPLAY INVISIBLE (-5925 -1825);
FORCEPROP 1 LASTPIN (-5975 -1950) $PN 1
J 0
(-5970 -1988);
DISPLAY 0.787234 (-5970 -1988);
FORCEPROP 1 LASTPIN (-5975 -2150) $PN 2
J 0
(-5970 -2140);
DISPLAY 0.787234 (-5970 -2140);
FORCEPROP 1 LAST PACK_TYPE 0402LF
J 0
(-5935 -2225);
DISPLAY 0.638298 (-5935 -2225);
FORCEPROP 1 LAST WATTAGE 1/16W
J 0
(-5935 -2075);
DISPLAY 0.638298 (-5935 -2075);
FORCEPROP 1 LAST TOLERANCE 5%
J 0
(-5930 -2025);
DISPLAY 0.638298 (-5930 -2025);
FORCEPROP 1 LAST VALUE 4.7K
J 0
(-5930 -1975);
DISPLAY 0.638298 (-5930 -1975);
FORCEPROP 1 LAST MATERIAL CHIP
J 0
(-5935 -2125);
DISPLAY 0.638298 (-5935 -2125);
FORCEPROP 2 LAST CDS_LIB pure_quanta
J 0
(-5975 -2050);
PAINT MONO (-5975 -2050);
DISPLAY INVISIBLE (-5975 -2050);
FORCEPROP 1 LAST PATH I396
J 0
(-5925 -1875);
DISPLAY 0.978723 (-5925 -1875);
PAINT WHITE (-5925 -1875);
DISPLAY INVISIBLE (-5925 -1875);
FORCEPROP 1 LAST PART_NUMBER CS24702JB10
J 0
(-5935 -2175);
DISPLAY 0.638298 (-5935 -2175);
DISPLAY INVISIBLE (-5935 -2175);
FORCEADD UNIVERSAL_GND..1
(-5975 -3100);
FORCEPROP 3 LASTPIN (-5975 -3050) SIG_NAME GND\g
J 0
(-5965 -3040);
DISPLAY 0.659574 (-5965 -3040);
PAINT MONO (-5965 -3040);
DISPLAY INVISIBLE (-5965 -3040);
FORCEPROP 2 LAST CDS_LIB pure_quanta_power
J 0
(-5975 -3100);
DISPLAY INVISIBLE (-5975 -3100);
FORCEPROP 1 LAST HDL_POWER GND
J 1
(-5950 -3175);
DISPLAY 0.872340 (-5950 -3175);
PAINT GREEN (-5950 -3175);
DISPLAY INVISIBLE (-5950 -3175);
FORCEPROP 1 LAST PATH I397
J 0
(-5900 -3100);
DISPLAY 0.872340 (-5900 -3100);
PAINT AQUA (-5900 -3100);
DISPLAY INVISIBLE (-5900 -3100);
FORCEADD LTC4307CMS8..1
(-3100 -3400);
FORCEPROP 1 LAST LOCATION U192
J 0
(-3350 -3095);
DISPLAY 0.723404 (-3350 -3095);
PAINT GREEN (-3350 -3095);
FORCEPROP 2 LAST $SEC 1
J 0
(-3350 -2950);
DISPLAY 0.680851 (-3350 -2950);
PAINT MONO (-3350 -2950);
DISPLAY INVISIBLE (-3350 -2950);
FORCEPROP 2 LAST CDS_SEC 1
J 0
(-3350 -2950);
DISPLAY 1.021277 (-3350 -2950);
DISPLAY INVISIBLE (-3350 -2950);
FORCEPROP 2 LASTPIN (-3500 -3250) $PN 1
J 2
(-3510 -3240);
DISPLAY 0.680851 (-3510 -3240);
PAINT MONO (-3510 -3240);
FORCEPROP 2 LASTPIN (-3500 -3550) $PN 4
J 2
(-3510 -3540);
DISPLAY 0.680851 (-3510 -3540);
PAINT MONO (-3510 -3540);
FORCEPROP 2 LASTPIN (-2700 -3550) $PN 5
J 0
(-2690 -3540);
DISPLAY 0.680851 (-2690 -3540);
PAINT MONO (-2690 -3540);
FORCEPROP 2 LASTPIN (-3500 -3350) $PN 3
J 2
(-3510 -3340);
DISPLAY 0.680851 (-3510 -3340);
PAINT MONO (-3510 -3340);
FORCEPROP 2 LASTPIN (-2700 -3350) $PN 2
J 0
(-2690 -3340);
DISPLAY 0.680851 (-2690 -3340);
PAINT MONO (-2690 -3340);
FORCEPROP 2 LASTPIN (-3500 -3450) $PN 6
J 2
(-3510 -3440);
DISPLAY 0.680851 (-3510 -3440);
PAINT MONO (-3510 -3440);
FORCEPROP 2 LASTPIN (-2700 -3450) $PN 7
J 0
(-2690 -3440);
DISPLAY 0.680851 (-2690 -3440);
PAINT MONO (-2690 -3440);
FORCEPROP 2 LASTPIN (-2700 -3250) $PN 8
J 0
(-2690 -3240);
DISPLAY 0.680851 (-2690 -3240);
PAINT MONO (-2690 -3240);
FORCEPROP 2 LAST PART_TYPE SMLF
J 0
(-3350 -3000);
DISPLAY 1.021277 (-3350 -3000);
FORCEPROP 1 LAST MATERIAL IC
J 0
(-3350 -3190);
DISPLAY 0.723404 (-3350 -3190);
PAINT GREEN (-3350 -3190);
FORCEPROP 2 LAST VALUE LTC4307CMS8
J 0
(-3350 -3050);
DISPLAY 1.021277 (-3350 -3050);
FORCEPROP 1 LAST NEEDS_NO_SIZE TRUE
J 0
(-3100 -3400);
DISPLAY 0.468085 (-3100 -3400);
PAINT GREEN (-3100 -3400);
DISPLAY INVISIBLE (-3100 -3400);
FORCEPROP 2 LAST CDS_LIB pure_quanta
J 0
(-3100 -3400);
DISPLAY INVISIBLE (-3100 -3400);
FORCEPROP 1 LAST PATH I398
J 0
(-2875 -3195);
DISPLAY 0.723404 (-2875 -3195);
PAINT GREEN (-2875 -3195);
DISPLAY INVISIBLE (-2875 -3195);
FORCEPROP 1 LAST PART_NUMBER AL004307000
J 0
(-3350 -3140);
DISPLAY 0.723404 (-3350 -3140);
PAINT GREEN (-3350 -3140);
DISPLAY INVISIBLE (-3350 -3140);
FORCEADD OFFPAGE..4
R 2
(-5500 -3350);
FORCEPROP 2 LAST $XR1 151 
J 0
(-5872 -3350);
DISPLAY 0.638298 (-5872 -3350);
PAINT MONO (-5872 -3350);
FORCEPROP 2 LAST $XR0 150 
J 0
(-5752 -3350);
DISPLAY 0.638298 (-5752 -3350);
PAINT MONO (-5752 -3350);
FORCEPROP 2 LAST CDS_LIB standard
J 2
(-5500 -3350);
DISPLAY INVISIBLE (-5500 -3350);
FORCEPROP 1 LAST OFFPAGE TRUE
J 2
(-5825 -3475);
DISPLAY 0.872340 (-5825 -3475);
PAINT GREEN (-5825 -3475);
DISPLAY INVISIBLE (-5825 -3475);
FORCEPROP 1 LAST COMMENT_BODY TRUE
J 2
(-5475 -3450);
DISPLAY 0.872340 (-5475 -3450);
PAINT PEACH (-5475 -3450);
DISPLAY INVISIBLE (-5475 -3450);
FORCEPROP 2 LAST PATH I403
J 2
(-6325 -3300);
DISPLAY 1.021277 (-6325 -3300);
DISPLAY INVISIBLE (-6325 -3300);
FORCEADD OFFPAGE..3
R 2
(-5500 -3450);
FORCEPROP 2 LAST $XR1 151 
J 0
(-5930 -3450);
DISPLAY 0.638298 (-5930 -3450);
PAINT MONO (-5930 -3450);
FORCEPROP 2 LAST $XR0 150 
J 0
(-5810 -3450);
DISPLAY 0.638298 (-5810 -3450);
PAINT MONO (-5810 -3450);
FORCEPROP 2 LAST CDS_LIB standard
J 2
(-5500 -3450);
DISPLAY INVISIBLE (-5500 -3450);
FORCEPROP 1 LAST OFFPAGE TRUE
J 2
(-5825 -3575);
DISPLAY 0.872340 (-5825 -3575);
PAINT GREEN (-5825 -3575);
DISPLAY INVISIBLE (-5825 -3575);
FORCEPROP 1 LAST COMMENT_BODY TRUE
J 2
(-5450 -3550);
DISPLAY 0.872340 (-5450 -3550);
PAINT GREEN (-5450 -3550);
DISPLAY INVISIBLE (-5450 -3550);
FORCEPROP 2 LAST PATH I404
J 2
(-6225 -3400);
DISPLAY 1.021277 (-6225 -3400);
DISPLAY INVISIBLE (-6225 -3400);
FORCEADD UNIVERSAL_GND..1
(-3525 -3650);
FORCEPROP 3 LASTPIN (-3525 -3600) SIG_NAME GND\g
J 0
(-3515 -3590);
DISPLAY 0.659574 (-3515 -3590);
PAINT MONO (-3515 -3590);
DISPLAY INVISIBLE (-3515 -3590);
FORCEPROP 2 LAST CDS_LIB pure_quanta_power
J 0
(-3525 -3650);
DISPLAY INVISIBLE (-3525 -3650);
FORCEPROP 1 LAST HDL_POWER GND
J 1
(-3500 -3725);
DISPLAY 0.872340 (-3500 -3725);
PAINT GREEN (-3500 -3725);
DISPLAY INVISIBLE (-3500 -3725);
FORCEPROP 1 LAST PATH I405
J 0
(-3450 -3650);
DISPLAY 0.872340 (-3450 -3650);
PAINT AQUA (-3450 -3650);
DISPLAY INVISIBLE (-3450 -3650);
FORCEADD Q_CAP..1
R 2
(-2250 -2825);
FORCEPROP 1 LAST LOCATION C1751
J 2
(-2300 -2725);
DISPLAY 0.638298 (-2300 -2725);
FORCEPROP 2 LAST $SEC 1
J 0
(-2300 -2625);
DISPLAY 0.680851 (-2300 -2625);
PAINT MONO (-2300 -2625);
DISPLAY INVISIBLE (-2300 -2625);
FORCEPROP 2 LAST CDS_SEC 1
J 0
(-2300 -2625);
DISPLAY 1.021277 (-2300 -2625);
DISPLAY INVISIBLE (-2300 -2625);
FORCEPROP 1 LASTPIN (-2250 -2725) $PN 1
J 2
(-2260 -2745);
DISPLAY 0.787234 (-2260 -2745);
FORCEPROP 1 LASTPIN (-2250 -2925) $PN 2
J 2
(-2260 -2945);
DISPLAY 0.787234 (-2260 -2945);
FORCEPROP 1 LAST MATERIAL X7R
J 2
(-2300 -2925);
DISPLAY 0.510638 (-2300 -2925);
FORCEPROP 1 LAST VOLTAGE 25V
J 2
(-2300 -2825);
DISPLAY 0.510638 (-2300 -2825);
FORCEPROP 1 LAST TOLERANCE 10%
J 2
(-2300 -2875);
DISPLAY 0.510638 (-2300 -2875);
FORCEPROP 1 LAST VALUE 0.1UF
J 2
(-2300 -2775);
DISPLAY 0.510638 (-2300 -2775);
FORCEPROP 1 LAST PACK_TYPE 0402
J 2
(-2300 -3025);
DISPLAY 0.510638 (-2300 -3025);
FORCEPROP 2 LAST CDS_LIB pure_quanta
J 2
(-2250 -2825);
PAINT MONO (-2250 -2825);
DISPLAY INVISIBLE (-2250 -2825);
FORCEPROP 1 LAST PATH I412
J 2
(-2300 -2675);
DISPLAY 0.978723 (-2300 -2675);
PAINT WHITE (-2300 -2675);
DISPLAY INVISIBLE (-2300 -2675);
FORCEPROP 1 LAST PART_NUMBER CH4104K1B00
J 2
(-2300 -2975);
DISPLAY 0.510638 (-2300 -2975);
DISPLAY INVISIBLE (-2300 -2975);
FORCEADD UNIVERSAL_GND..1
(-2250 -3075);
FORCEPROP 3 LASTPIN (-2250 -3025) SIG_NAME GND\g
J 0
(-2240 -3015);
DISPLAY 0.659574 (-2240 -3015);
PAINT MONO (-2240 -3015);
DISPLAY INVISIBLE (-2240 -3015);
FORCEPROP 2 LAST CDS_LIB pure_quanta_power
J 0
(-2250 -3075);
DISPLAY INVISIBLE (-2250 -3075);
FORCEPROP 1 LAST HDL_POWER GND
J 1
(-2225 -3150);
DISPLAY 0.872340 (-2225 -3150);
PAINT GREEN (-2225 -3150);
DISPLAY INVISIBLE (-2225 -3150);
FORCEPROP 1 LAST PATH I413
J 0
(-2175 -3075);
DISPLAY 0.872340 (-2175 -3075);
PAINT AQUA (-2175 -3075);
DISPLAY INVISIBLE (-2175 -3075);
FORCEADD UNIVERSAL_POWER..1
(-2600 -2550);
FORCEPROP 3 LASTPIN (-2600 -2600) SIG_NAME P3V3_AUX\g
J 0
(-2590 -2590);
DISPLAY 0.659574 (-2590 -2590);
PAINT MONO (-2590 -2590);
DISPLAY INVISIBLE (-2590 -2590);
FORCEPROP 1 LAST HDL_POWER P3V3_AUX
J 1
(-2600 -2500);
DISPLAY 0.872340 (-2600 -2500);
PAINT GREEN (-2600 -2500);
FORCEPROP 2 LAST CDS_LIB pure_quanta_power
J 0
(-2600 -2550);
PAINT MONO (-2600 -2550);
DISPLAY INVISIBLE (-2600 -2550);
FORCEPROP 1 LAST PATH I414
J 0
(-2550 -2525);
DISPLAY 0.872340 (-2550 -2525);
PAINT AQUA (-2550 -2525);
DISPLAY INVISIBLE (-2550 -2525);
FORCEADD Q_RES..1
(-4650 -3250);
FORCEPROP 1 LAST LOCATION R2796
J 0
(-4850 -3250);
DISPLAY 0.638298 (-4850 -3250);
FORCEPROP 2 LAST $SEC 1
J 0
(-4700 -3050);
DISPLAY 0.680851 (-4700 -3050);
PAINT MONO (-4700 -3050);
DISPLAY INVISIBLE (-4700 -3050);
FORCEPROP 2 LAST CDS_SEC 1
J 0
(-4700 -3050);
DISPLAY 1.021277 (-4700 -3050);
DISPLAY INVISIBLE (-4700 -3050);
FORCEPROP 1 LASTPIN (-4750 -3250) $PN 1
J 0
(-4738 -3238);
DISPLAY 0.787234 (-4738 -3238);
FORCEPROP 1 LASTPIN (-4550 -3250) $PN 2
J 0
(-4588 -3238);
DISPLAY 0.787234 (-4588 -3238);
FORCEPROP 1 LAST MATERIAL CHIP
J 0
(-4400 -3250);
DISPLAY 0.404255 (-4400 -3250);
FORCEPROP 1 LAST TOLERANCE 5%
J 0
(-4450 -3250);
DISPLAY 0.404255 (-4450 -3250);
FORCEPROP 1 LAST VALUE 0
J 2
(-4475 -3250);
DISPLAY 0.404255 (-4475 -3250);
FORCEPROP 2 LAST CDS_LIB pure_quanta
J 0
(-4650 -3250);
PAINT MONO (-4650 -3250);
DISPLAY INVISIBLE (-4650 -3250);
FORCEPROP 1 LAST PACK_TYPE 0402LF
J 0
(-4400 -3250);
DISPLAY 0.638298 (-4400 -3250);
DISPLAY INVISIBLE (-4400 -3250);
FORCEPROP 1 LAST WATTAGE 1/16W
J 2
(-4675 -3400);
DISPLAY 0.978723 (-4675 -3400);
DISPLAY INVISIBLE (-4675 -3400);
FORCEPROP 1 LAST PATH I420
J 0
(-4700 -3100);
DISPLAY 0.978723 (-4700 -3100);
PAINT WHITE (-4700 -3100);
DISPLAY INVISIBLE (-4700 -3100);
FORCEPROP 1 LAST PART_NUMBER CS00002JB13
J 0
(-4775 -3400);
DISPLAY 0.510638 (-4775 -3400);
DISPLAY INVISIBLE (-4775 -3400);
FORCEPROP 1 LAST LOCATION R2796
J 0
(-4700 -3050);
DISPLAY 1.021277 (-4700 -3050);
DISPLAY INVISIBLE (-4700 -3050);
FORCEADD Q_RES..1
(-1075 -3350);
FORCEPROP 1 LAST LOCATION R2811
J 0
(-1300 -3350);
DISPLAY 0.638298 (-1300 -3350);
FORCEPROP 0 LAST $SEC 1
J 0
(-1300 -3300);
DISPLAY 0.680851 (-1300 -3300);
PAINT MONO (-1300 -3300);
DISPLAY INVISIBLE (-1300 -3300);
FORCEPROP 0 LAST CDS_SEC 1
J 0
(-1300 -3300);
DISPLAY 1.021277 (-1300 -3300);
DISPLAY INVISIBLE (-1300 -3300);
FORCEPROP 1 LASTPIN (-1175 -3350) $PN 1
J 0
(-1163 -3338);
DISPLAY 0.787234 (-1163 -3338);
PAINT MONO (-1163 -3338);
FORCEPROP 1 LASTPIN (-975 -3350) $PN 2
J 0
(-1013 -3338);
DISPLAY 0.787234 (-1013 -3338);
PAINT MONO (-1013 -3338);
FORCEPROP 1 LAST VALUE 33.2
J 2
(-875 -3350);
DISPLAY 0.510638 (-875 -3350);
FORCEPROP 1 LAST MATERIAL CHIP
J 0
(-775 -3350);
DISPLAY 0.510638 (-775 -3350);
FORCEPROP 1 LAST TOLERANCE 1%
J 0
(-850 -3350);
DISPLAY 0.510638 (-850 -3350);
FORCEPROP 2 LAST CDS_LIB pure_quanta
J 0
(-1075 -3350);
DISPLAY INVISIBLE (-1075 -3350);
FORCEPROP 1 LAST WATTAGE 1/16W
J 2
(-975 -3250);
DISPLAY 0.404255 (-975 -3250);
DISPLAY INVISIBLE (-975 -3250);
FORCEPROP 1 LAST PACK_TYPE 0402LF
J 0
(-1200 -3250);
DISPLAY 0.404255 (-1200 -3250);
DISPLAY INVISIBLE (-1200 -3250);
FORCEPROP 1 LAST PATH I425
J 0
(-1125 -3200);
DISPLAY 0.978723 (-1125 -3200);
PAINT WHITE (-1125 -3200);
DISPLAY INVISIBLE (-1125 -3200);
FORCEPROP 1 LAST PART_NUMBER CS03322FB03
J 0
(-1200 -3300);
DISPLAY 0.404255 (-1200 -3300);
DISPLAY INVISIBLE (-1200 -3300);
FORCEADD Q_RES..1
(-1075 -3450);
FORCEPROP 1 LAST LOCATION R2812
J 0
(-1300 -3450);
DISPLAY 0.638298 (-1300 -3450);
FORCEPROP 0 LAST $SEC 1
J 0
(-1300 -3400);
DISPLAY 0.680851 (-1300 -3400);
PAINT MONO (-1300 -3400);
DISPLAY INVISIBLE (-1300 -3400);
FORCEPROP 0 LAST CDS_SEC 1
J 0
(-1300 -3400);
DISPLAY 1.021277 (-1300 -3400);
DISPLAY INVISIBLE (-1300 -3400);
FORCEPROP 1 LASTPIN (-1175 -3450) $PN 1
J 0
(-1163 -3438);
DISPLAY 0.787234 (-1163 -3438);
PAINT MONO (-1163 -3438);
FORCEPROP 1 LASTPIN (-975 -3450) $PN 2
J 0
(-1013 -3438);
DISPLAY 0.787234 (-1013 -3438);
PAINT MONO (-1013 -3438);
FORCEPROP 1 LAST VALUE 33.2
J 2
(-875 -3450);
DISPLAY 0.510638 (-875 -3450);
FORCEPROP 1 LAST MATERIAL CHIP
J 0
(-775 -3450);
DISPLAY 0.510638 (-775 -3450);
FORCEPROP 1 LAST TOLERANCE 1%
J 0
(-850 -3450);
DISPLAY 0.510638 (-850 -3450);
FORCEPROP 1 LAST WATTAGE 1/16W
J 2
(-975 -3350);
DISPLAY 0.404255 (-975 -3350);
DISPLAY INVISIBLE (-975 -3350);
FORCEPROP 1 LAST PACK_TYPE 0402LF
J 0
(-1200 -3350);
DISPLAY 0.404255 (-1200 -3350);
DISPLAY INVISIBLE (-1200 -3350);
FORCEPROP 2 LAST CDS_LIB pure_quanta
J 0
(-1075 -3450);
DISPLAY INVISIBLE (-1075 -3450);
FORCEPROP 1 LAST PATH I426
J 0
(-1125 -3300);
DISPLAY 0.978723 (-1125 -3300);
PAINT WHITE (-1125 -3300);
DISPLAY INVISIBLE (-1125 -3300);
FORCEPROP 1 LAST PART_NUMBER CS03322FB03
J 0
(-1200 -3400);
DISPLAY 0.404255 (-1200 -3400);
DISPLAY INVISIBLE (-1200 -3400);
FORCEADD OFFPAGE..3
(475 -3450);
FORCEPROP 2 LAST $XR0 241 
J 0
(689 -3450);
DISPLAY 0.638298 (689 -3450);
PAINT MONO (689 -3450);
FORCEPROP 2 LAST CDS_LIB standard
J 0
(475 -3450);
DISPLAY INVISIBLE (475 -3450);
FORCEPROP 1 LAST OFFPAGE TRUE
J 0
(800 -3575);
DISPLAY 0.872340 (800 -3575);
PAINT GREEN (800 -3575);
DISPLAY INVISIBLE (800 -3575);
FORCEPROP 1 LAST COMMENT_BODY TRUE
J 0
(425 -3550);
DISPLAY 0.872340 (425 -3550);
PAINT GREEN (425 -3550);
DISPLAY INVISIBLE (425 -3550);
FORCEPROP 2 LAST PATH I427
J 0
(1200 -3400);
DISPLAY 1.021277 (1200 -3400);
DISPLAY INVISIBLE (1200 -3400);
FORCEADD OFFPAGE..4
(475 -3350);
FORCEPROP 2 LAST $XR0 241 
J 0
(661 -3350);
DISPLAY 0.638298 (661 -3350);
PAINT MONO (661 -3350);
FORCEPROP 2 LAST CDS_LIB standard
J 0
(475 -3350);
DISPLAY INVISIBLE (475 -3350);
FORCEPROP 1 LAST OFFPAGE TRUE
J 0
(800 -3475);
DISPLAY 0.872340 (800 -3475);
PAINT GREEN (800 -3475);
DISPLAY INVISIBLE (800 -3475);
FORCEPROP 1 LAST COMMENT_BODY TRUE
J 0
(450 -3450);
DISPLAY 0.872340 (450 -3450);
PAINT PEACH (450 -3450);
DISPLAY INVISIBLE (450 -3450);
FORCEPROP 2 LAST PATH I428
J 0
(1300 -3300);
DISPLAY 1.021277 (1300 -3300);
DISPLAY INVISIBLE (1300 -3300);
FORCEADD Q_RES..1
(-3125 -3800);
FORCEPROP 1 LAST LOCATION R2800
J 0
(-3300 -3800);
DISPLAY 0.638298 (-3300 -3800);
FORCEPROP 0 LAST $SEC 1
J 0
(-3000 -3700);
DISPLAY 0.680851 (-3000 -3700);
PAINT MONO (-3000 -3700);
DISPLAY INVISIBLE (-3000 -3700);
FORCEPROP 0 LAST CDS_SEC 1
J 0
(-3000 -3700);
DISPLAY 1.021277 (-3000 -3700);
DISPLAY INVISIBLE (-3000 -3700);
FORCEPROP 1 LASTPIN (-3225 -3800) $PN 1
J 0
(-3213 -3788);
DISPLAY 0.787234 (-3213 -3788);
PAINT MONO (-3213 -3788);
FORCEPROP 1 LASTPIN (-3025 -3800) $PN 2
J 0
(-3063 -3788);
DISPLAY 0.787234 (-3063 -3788);
PAINT MONO (-3063 -3788);
FORCEPROP 1 LAST MATERIAL EMPTY
J 0
(-2825 -3800);
DISPLAY 0.510638 (-2825 -3800);
PAINT RED (-2825 -3800);
FORCEPROP 1 LAST VALUE 0
J 2
(-2975 -3800);
DISPLAY 0.510638 (-2975 -3800);
FORCEPROP 1 LAST WATTAGE 1/16W
J 2
(-3000 -3900);
DISPLAY 0.404255 (-3000 -3900);
DISPLAY INVISIBLE (-3000 -3900);
FORCEPROP 1 LAST TOLERANCE 5%
J 0
(-2900 -3800);
DISPLAY 0.510638 (-2900 -3800);
DISPLAY INVISIBLE (-2900 -3800);
FORCEPROP 1 LAST PACK_TYPE 0402LF
J 0
(-3225 -3900);
DISPLAY 0.404255 (-3225 -3900);
DISPLAY INVISIBLE (-3225 -3900);
FORCEPROP 2 LAST CDS_LIB pure_quanta
J 0
(-3125 -3800);
DISPLAY INVISIBLE (-3125 -3800);
FORCEPROP 1 LAST PATH I429
J 0
(-3175 -3650);
DISPLAY 0.978723 (-3175 -3650);
PAINT WHITE (-3175 -3650);
DISPLAY INVISIBLE (-3175 -3650);
FORCEPROP 1 LAST PART_NUMBER CS00002JB13
J 0
(-3225 -3850);
DISPLAY 0.404255 (-3225 -3850);
DISPLAY INVISIBLE (-3225 -3850);
FORCEADD Q_RES..1
(-3125 -3875);
FORCEPROP 1 LAST LOCATION R2801
J 0
(-3300 -3875);
DISPLAY 0.638298 (-3300 -3875);
FORCEPROP 2 LAST $SEC 1
J 0
(-3175 -3675);
DISPLAY 0.680851 (-3175 -3675);
PAINT MONO (-3175 -3675);
DISPLAY INVISIBLE (-3175 -3675);
FORCEPROP 2 LAST CDS_SEC 1
J 0
(-3175 -3675);
DISPLAY 1.021277 (-3175 -3675);
DISPLAY INVISIBLE (-3175 -3675);
FORCEPROP 1 LASTPIN (-3225 -3875) $PN 1
J 0
(-3213 -3863);
DISPLAY 0.787234 (-3213 -3863);
PAINT MONO (-3213 -3863);
FORCEPROP 1 LASTPIN (-3025 -3875) $PN 2
J 0
(-3063 -3863);
DISPLAY 0.787234 (-3063 -3863);
PAINT MONO (-3063 -3863);
FORCEPROP 1 LAST VALUE 0
J 2
(-2975 -3875);
DISPLAY 0.510638 (-2975 -3875);
FORCEPROP 1 LAST TOLERANCE 5%
J 0
(-2900 -3875);
DISPLAY 0.510638 (-2900 -3875);
FORCEPROP 1 LAST MATERIAL EMPTY
J 0
(-2825 -3875);
DISPLAY 0.510638 (-2825 -3875);
PAINT RED (-2825 -3875);
FORCEPROP 1 LAST WATTAGE 1/16W
J 2
(-3000 -3975);
DISPLAY 0.404255 (-3000 -3975);
FORCEPROP 1 LAST PACK_TYPE 0402LF
J 0
(-3225 -3975);
DISPLAY 0.404255 (-3225 -3975);
FORCEPROP 2 LAST CDS_LIB pure_quanta
J 0
(-3125 -3875);
DISPLAY INVISIBLE (-3125 -3875);
FORCEPROP 1 LAST PATH I430
J 0
(-3175 -3725);
DISPLAY 0.978723 (-3175 -3725);
PAINT WHITE (-3175 -3725);
DISPLAY INVISIBLE (-3175 -3725);
FORCEPROP 1 LAST PART_NUMBER CS00002JB13
J 0
(-3225 -3925);
DISPLAY 0.404255 (-3225 -3925);
DISPLAY INVISIBLE (-3225 -3925);
FORCEADD Q_RES..2
(-1800 -2900);
FORCEPROP 1 LAST LOCATION R2805
J 0
(-1755 -2775);
DISPLAY 0.638298 (-1755 -2775);
FORCEPROP 2 LAST $SEC 1
J 0
(-1750 -2675);
DISPLAY 0.680851 (-1750 -2675);
PAINT MONO (-1750 -2675);
DISPLAY INVISIBLE (-1750 -2675);
FORCEPROP 2 LAST CDS_SEC 1
J 0
(-1750 -2675);
DISPLAY 1.021277 (-1750 -2675);
DISPLAY INVISIBLE (-1750 -2675);
FORCEPROP 1 LASTPIN (-1800 -2800) $PN 1
J 0
(-1795 -2838);
DISPLAY 0.787234 (-1795 -2838);
FORCEPROP 1 LASTPIN (-1800 -3000) $PN 2
J 0
(-1795 -2990);
DISPLAY 0.787234 (-1795 -2990);
FORCEPROP 1 LAST MATERIAL EMPTY
J 0
(-1760 -2975);
DISPLAY 0.638298 (-1760 -2975);
FORCEPROP 1 LAST PACK_TYPE 0402LF
J 0
(-1760 -3025);
DISPLAY 0.638298 (-1760 -3025);
FORCEPROP 1 LAST WATTAGE 1/16W
J 0
(-1760 -2925);
DISPLAY 0.638298 (-1760 -2925);
FORCEPROP 1 LAST TOLERANCE 5%
J 0
(-1755 -2875);
DISPLAY 0.638298 (-1755 -2875);
FORCEPROP 1 LAST VALUE 4.7K
J 0
(-1755 -2825);
DISPLAY 0.638298 (-1755 -2825);
FORCEPROP 2 LAST CDS_LIB pure_quanta
J 0
(-1800 -2900);
PAINT MONO (-1800 -2900);
DISPLAY INVISIBLE (-1800 -2900);
FORCEPROP 1 LAST PATH I436
J 0
(-1750 -2725);
DISPLAY 0.978723 (-1750 -2725);
PAINT WHITE (-1750 -2725);
DISPLAY INVISIBLE (-1750 -2725);
FORCEPROP 1 LAST PART_NUMBER CS24702JB10
J 0
(-1760 -3075);
DISPLAY 0.638298 (-1760 -3075);
DISPLAY INVISIBLE (-1760 -3075);
FORCEADD UNIVERSAL_POWER..1
(-1800 -2600);
FORCEPROP 3 LASTPIN (-1800 -2650) SIG_NAME P3V3_AUX\g
J 0
(-1790 -2640);
DISPLAY 0.659574 (-1790 -2640);
PAINT MONO (-1790 -2640);
DISPLAY INVISIBLE (-1790 -2640);
FORCEPROP 1 LAST HDL_POWER P3V3_AUX
J 1
(-1800 -2550);
DISPLAY 0.872340 (-1800 -2550);
PAINT GREEN (-1800 -2550);
FORCEPROP 2 LAST CDS_LIB pure_quanta_power
J 0
(-1800 -2600);
PAINT MONO (-1800 -2600);
DISPLAY INVISIBLE (-1800 -2600);
FORCEPROP 1 LAST PATH I437
J 0
(-1750 -2575);
DISPLAY 0.872340 (-1750 -2575);
PAINT AQUA (-1750 -2575);
DISPLAY INVISIBLE (-1750 -2575);
FORCEADD Q_RES..2
(-1550 -2925);
FORCEPROP 1 LAST LOCATION R2807
J 0
(-1505 -2800);
DISPLAY 0.638298 (-1505 -2800);
FORCEPROP 2 LAST $SEC 1
J 0
(-1500 -2700);
DISPLAY 0.680851 (-1500 -2700);
PAINT MONO (-1500 -2700);
DISPLAY INVISIBLE (-1500 -2700);
FORCEPROP 2 LAST CDS_SEC 1
J 0
(-1500 -2700);
DISPLAY 1.021277 (-1500 -2700);
DISPLAY INVISIBLE (-1500 -2700);
FORCEPROP 1 LASTPIN (-1550 -2825) $PN 1
J 0
(-1545 -2863);
DISPLAY 0.787234 (-1545 -2863);
FORCEPROP 1 LASTPIN (-1550 -3025) $PN 2
J 0
(-1545 -3015);
DISPLAY 0.787234 (-1545 -3015);
FORCEPROP 1 LAST MATERIAL EMPTY
J 0
(-1510 -3000);
DISPLAY 0.638298 (-1510 -3000);
FORCEPROP 1 LAST WATTAGE 1/16W
J 0
(-1510 -2950);
DISPLAY 0.638298 (-1510 -2950);
FORCEPROP 1 LAST TOLERANCE 5%
J 0
(-1505 -2900);
DISPLAY 0.638298 (-1505 -2900);
FORCEPROP 1 LAST PACK_TYPE 0402LF
J 0
(-1510 -3050);
DISPLAY 0.638298 (-1510 -3050);
FORCEPROP 1 LAST VALUE 4.7K
J 0
(-1505 -2850);
DISPLAY 0.638298 (-1505 -2850);
FORCEPROP 2 LAST CDS_LIB pure_quanta
J 0
(-1550 -2925);
PAINT MONO (-1550 -2925);
DISPLAY INVISIBLE (-1550 -2925);
FORCEPROP 1 LAST PATH I438
J 0
(-1500 -2750);
DISPLAY 0.978723 (-1500 -2750);
PAINT WHITE (-1500 -2750);
DISPLAY INVISIBLE (-1500 -2750);
FORCEPROP 1 LAST PART_NUMBER CS24702JB10
J 0
(-1510 -3100);
DISPLAY 0.638298 (-1510 -3100);
DISPLAY INVISIBLE (-1510 -3100);
FORCEADD OFFPAGE..5
(-7050 725);
FORCEPROP 2 LAST $XR0 258 
J 0
(-7305 725);
DISPLAY 0.638298 (-7305 725);
PAINT MONO (-7305 725);
FORCEPROP 2 LAST CDS_LIB standard
J 0
(-7050 725);
DISPLAY INVISIBLE (-7050 725);
FORCEPROP 1 LAST OFFPAGE TRUE
J 0
(-6725 600);
DISPLAY 0.872340 (-6725 600);
DISPLAY INVISIBLE (-6725 600);
FORCEPROP 1 LAST COMMENT_BODY TRUE
J 0
(-6950 650);
DISPLAY 0.872340 (-6950 650);
PAINT GREEN (-6950 650);
DISPLAY INVISIBLE (-6950 650);
FORCEPROP 2 LAST PATH I439
J 0
(-7325 775);
DISPLAY 1.021277 (-7325 775);
DISPLAY INVISIBLE (-7325 775);
FORCEADD Q_RES..1
(-2150 625);
FORCEPROP 1 LAST LOCATION R2906
J 0
(-2375 625);
DISPLAY 0.638298 (-2375 625);
FORCEPROP 2 LAST $SEC 1
J 0
(-2200 825);
DISPLAY 0.680851 (-2200 825);
PAINT MONO (-2200 825);
DISPLAY INVISIBLE (-2200 825);
FORCEPROP 2 LAST CDS_SEC 1
J 0
(-2200 825);
DISPLAY 1.021277 (-2200 825);
DISPLAY INVISIBLE (-2200 825);
FORCEPROP 1 LASTPIN (-2250 625) $PN 1
J 0
(-2238 637);
DISPLAY 0.787234 (-2238 637);
PAINT MONO (-2238 637);
FORCEPROP 1 LASTPIN (-2050 625) $PN 2
J 0
(-2088 637);
DISPLAY 0.787234 (-2088 637);
PAINT MONO (-2088 637);
FORCEPROP 1 LAST TOLERANCE 5%
J 0
(-1925 625);
DISPLAY 0.404255 (-1925 625);
FORCEPROP 1 LAST VALUE 0
J 2
(-1975 625);
DISPLAY 0.404255 (-1975 625);
FORCEPROP 1 LAST MATERIAL CHIP
J 0
(-1850 625);
DISPLAY 0.404255 (-1850 625);
FORCEPROP 2 LAST CDS_LIB pure_quanta
J 0
(-2150 625);
DISPLAY INVISIBLE (-2150 625);
FORCEPROP 1 LAST WATTAGE 1/16W
J 2
(-2175 475);
DISPLAY 0.978723 (-2175 475);
DISPLAY INVISIBLE (-2175 475);
FORCEPROP 1 LAST PACK_TYPE 0402LF
J 0
(-1900 625);
DISPLAY 0.638298 (-1900 625);
DISPLAY INVISIBLE (-1900 625);
FORCEPROP 1 LAST PATH I440
J 0
(-2200 775);
DISPLAY 0.978723 (-2200 775);
PAINT WHITE (-2200 775);
DISPLAY INVISIBLE (-2200 775);
FORCEPROP 1 LAST PART_NUMBER CS00002JB13
J 0
(-2275 475);
DISPLAY 0.510638 (-2275 475);
DISPLAY INVISIBLE (-2275 475);
FORCEADD Q_RES..1
(-5750 675);
FORCEPROP 1 LAST LOCATION R2905
J 0
(-5950 675);
DISPLAY 0.638298 (-5950 675);
FORCEPROP 2 LAST $SEC 1
J 0
(-5800 875);
DISPLAY 0.680851 (-5800 875);
PAINT MONO (-5800 875);
DISPLAY INVISIBLE (-5800 875);
FORCEPROP 2 LAST CDS_SEC 1
J 0
(-5800 875);
DISPLAY 1.021277 (-5800 875);
DISPLAY INVISIBLE (-5800 875);
FORCEPROP 1 LASTPIN (-5850 675) $PN 1
J 0
(-5838 687);
DISPLAY 0.787234 (-5838 687);
PAINT MONO (-5838 687);
FORCEPROP 1 LASTPIN (-5650 675) $PN 2
J 0
(-5688 687);
DISPLAY 0.787234 (-5688 687);
PAINT MONO (-5688 687);
FORCEPROP 1 LAST MATERIAL CHIP
J 0
(-5450 675);
DISPLAY 0.404255 (-5450 675);
FORCEPROP 1 LAST TOLERANCE 5%
J 0
(-5525 675);
DISPLAY 0.404255 (-5525 675);
FORCEPROP 1 LAST VALUE 0
J 2
(-5575 675);
DISPLAY 0.404255 (-5575 675);
FORCEPROP 2 LAST CDS_LIB pure_quanta
J 0
(-5750 675);
DISPLAY INVISIBLE (-5750 675);
FORCEPROP 1 LAST PACK_TYPE 0402LF
J 0
(-5500 675);
DISPLAY 0.638298 (-5500 675);
DISPLAY INVISIBLE (-5500 675);
FORCEPROP 1 LAST WATTAGE 1/16W
J 2
(-5775 525);
DISPLAY 0.978723 (-5775 525);
DISPLAY INVISIBLE (-5775 525);
FORCEPROP 1 LAST PATH I441
J 0
(-5800 825);
DISPLAY 0.978723 (-5800 825);
PAINT WHITE (-5800 825);
DISPLAY INVISIBLE (-5800 825);
FORCEPROP 1 LAST PART_NUMBER CS00002JB13
J 0
(-5875 525);
DISPLAY 0.510638 (-5875 525);
DISPLAY INVISIBLE (-5875 525);
FORCEADD OFFPAGE..5
R 2
(-5050 -2375);
FORCEPROP 2 LAST $XR0 130 
J 0
(-4861 -2375);
DISPLAY 0.638298 (-4861 -2375);
PAINT MONO (-4861 -2375);
FORCEPROP 2 LAST CDS_LIB standard
J 2
(-5050 -2375);
DISPLAY INVISIBLE (-5050 -2375);
FORCEPROP 1 LAST OFFPAGE TRUE
J 2
(-5375 -2500);
DISPLAY 0.872340 (-5375 -2500);
DISPLAY INVISIBLE (-5375 -2500);
FORCEPROP 1 LAST COMMENT_BODY TRUE
J 2
(-5150 -2450);
DISPLAY 0.872340 (-5150 -2450);
PAINT GREEN (-5150 -2450);
DISPLAY INVISIBLE (-5150 -2450);
FORCEPROP 2 LAST PATH I444
J 2
(-5100 -2300);
DISPLAY 1.021277 (-5100 -2300);
DISPLAY INVISIBLE (-5100 -2300);
FORCEADD OFFPAGE..1
(-7050 625);
FORCEPROP 2 LAST $XR0 242 
J 0
(-7332 625);
DISPLAY 0.638298 (-7332 625);
PAINT MONO (-7332 625);
FORCEPROP 2 LAST CDS_LIB standard
J 0
(-7050 625);
DISPLAY INVISIBLE (-7050 625);
FORCEPROP 1 LAST OFFPAGE TRUE
J 0
(-6725 500);
DISPLAY 0.872340 (-6725 500);
DISPLAY INVISIBLE (-6725 500);
FORCEPROP 1 LAST COMMENT_BODY TRUE
J 0
(-6925 525);
DISPLAY 0.872340 (-6925 525);
PAINT GREEN (-6925 525);
DISPLAY INVISIBLE (-6925 525);
FORCEPROP 2 LAST PATH I450
J 0
(-7000 700);
DISPLAY 1.021277 (-7000 700);
DISPLAY INVISIBLE (-7000 700);
FORCEADD Q_CAP..2
(200 100);
FORCEPROP 1 LAST LOCATION C74
J 1
(50 100);
DISPLAY 0.638298 (50 100);
FORCEPROP 0 LAST $SEC 1
J 0
(50 175);
DISPLAY 0.680851 (50 175);
PAINT MONO (50 175);
DISPLAY INVISIBLE (50 175);
FORCEPROP 0 LAST CDS_SEC 1
J 0
(50 175);
DISPLAY 1.021277 (50 175);
DISPLAY INVISIBLE (50 175);
FORCEPROP 1 LASTPIN (100 100) $PN 1
J 0
(90 115);
DISPLAY 0.787234 (90 115);
PAINT MONO (90 115);
FORCEPROP 1 LASTPIN (300 100) $PN 2
J 0
(285 115);
DISPLAY 0.787234 (285 115);
PAINT MONO (285 115);
FORCEPROP 1 LAST VALUE 0.1UF
J 2
(200 0);
DISPLAY 0.638298 (200 0);
FORCEPROP 1 LAST MATERIAL EMPTY
J 0
(225 0);
DISPLAY 0.638298 (225 0);
PAINT RED (225 0);
FORCEPROP 2 LAST CDS_LIB pure_quanta
J 0
(200 100);
DISPLAY INVISIBLE (200 100);
FORCEPROP 1 LAST PACK_TYPE 0402
J 1
(200 -100);
DISPLAY 0.978723 (200 -100);
DISPLAY INVISIBLE (200 -100);
FORCEPROP 1 LAST TOLERANCE 10%
J 2
(200 -50);
DISPLAY 0.978723 (200 -50);
DISPLAY INVISIBLE (200 -50);
FORCEPROP 1 LAST VOLTAGE 25V
J 0
(200 0);
DISPLAY 0.978723 (200 0);
DISPLAY INVISIBLE (200 0);
FORCEPROP 1 LAST PATH I452
J 0
(200 300);
DISPLAY 0.978723 (200 300);
PAINT WHITE (200 300);
DISPLAY INVISIBLE (200 300);
FORCEPROP 1 LAST PART_NUMBER CH4104K1B00
J 1
(200 150);
DISPLAY 0.978723 (200 150);
DISPLAY INVISIBLE (200 150);
FORCEADD Q_CAP..2
(200 -50);
FORCEPROP 1 LAST LOCATION C64
J 1
(50 -50);
DISPLAY 0.638298 (50 -50);
FORCEPROP 0 LAST $SEC 1
J 0
(50 0);
DISPLAY 0.680851 (50 0);
PAINT MONO (50 0);
DISPLAY INVISIBLE (50 0);
FORCEPROP 0 LAST CDS_SEC 1
J 0
(50 0);
DISPLAY 1.021277 (50 0);
DISPLAY INVISIBLE (50 0);
FORCEPROP 1 LASTPIN (100 -50) $PN 1
J 0
(90 -35);
DISPLAY 0.787234 (90 -35);
PAINT MONO (90 -35);
FORCEPROP 1 LASTPIN (300 -50) $PN 2
J 0
(285 -35);
DISPLAY 0.787234 (285 -35);
PAINT MONO (285 -35);
FORCEPROP 1 LAST VALUE 0.1UF
J 2
(200 -150);
DISPLAY 0.638298 (200 -150);
FORCEPROP 1 LAST MATERIAL EMPTY
J 0
(225 -150);
DISPLAY 0.638298 (225 -150);
PAINT RED (225 -150);
FORCEPROP 2 LAST CDS_LIB pure_quanta
J 0
(200 -50);
DISPLAY INVISIBLE (200 -50);
FORCEPROP 1 LAST PACK_TYPE 0402
J 1
(200 -250);
DISPLAY 0.978723 (200 -250);
DISPLAY INVISIBLE (200 -250);
FORCEPROP 1 LAST TOLERANCE 10%
J 2
(200 -200);
DISPLAY 0.978723 (200 -200);
DISPLAY INVISIBLE (200 -200);
FORCEPROP 1 LAST VOLTAGE 25V
J 0
(200 -150);
DISPLAY 0.978723 (200 -150);
DISPLAY INVISIBLE (200 -150);
FORCEPROP 1 LAST PATH I453
J 0
(200 150);
DISPLAY 0.978723 (200 150);
PAINT WHITE (200 150);
DISPLAY INVISIBLE (200 150);
FORCEPROP 1 LAST PART_NUMBER CH4104K1B00
J 1
(200 0);
DISPLAY 0.978723 (200 0);
DISPLAY INVISIBLE (200 0);
FORCEADD Q_CAP..2
(200 -200);
FORCEPROP 1 LAST LOCATION C65
J 1
(50 -200);
DISPLAY 0.638298 (50 -200);
FORCEPROP 0 LAST $SEC 1
J 0
(50 -150);
DISPLAY 0.680851 (50 -150);
PAINT MONO (50 -150);
DISPLAY INVISIBLE (50 -150);
FORCEPROP 0 LAST CDS_SEC 1
J 0
(50 -150);
DISPLAY 1.021277 (50 -150);
DISPLAY INVISIBLE (50 -150);
FORCEPROP 1 LASTPIN (100 -200) $PN 1
J 0
(90 -185);
DISPLAY 0.787234 (90 -185);
PAINT MONO (90 -185);
FORCEPROP 1 LASTPIN (300 -200) $PN 2
J 0
(285 -185);
DISPLAY 0.787234 (285 -185);
PAINT MONO (285 -185);
FORCEPROP 1 LAST MATERIAL EMPTY
J 0
(225 -300);
DISPLAY 0.638298 (225 -300);
PAINT RED (225 -300);
FORCEPROP 1 LAST VALUE 0.1UF
J 2
(200 -300);
DISPLAY 0.638298 (200 -300);
FORCEPROP 2 LAST CDS_LIB pure_quanta
J 0
(200 -200);
DISPLAY INVISIBLE (200 -200);
FORCEPROP 1 LAST PACK_TYPE 0402
J 1
(200 -400);
DISPLAY 0.978723 (200 -400);
DISPLAY INVISIBLE (200 -400);
FORCEPROP 1 LAST TOLERANCE 10%
J 2
(200 -350);
DISPLAY 0.978723 (200 -350);
DISPLAY INVISIBLE (200 -350);
FORCEPROP 1 LAST VOLTAGE 25V
J 0
(200 -300);
DISPLAY 0.978723 (200 -300);
DISPLAY INVISIBLE (200 -300);
FORCEPROP 1 LAST PATH I454
J 0
(200 0);
DISPLAY 0.978723 (200 0);
PAINT WHITE (200 0);
DISPLAY INVISIBLE (200 0);
FORCEPROP 1 LAST PART_NUMBER CH4104K1B00
J 1
(200 -150);
DISPLAY 0.978723 (200 -150);
DISPLAY INVISIBLE (200 -150);
FORCEADD Q_CAP..2
(200 -350);
FORCEPROP 1 LAST LOCATION C66
J 1
(50 -350);
DISPLAY 0.638298 (50 -350);
FORCEPROP 0 LAST $SEC 1
J 0
(50 -300);
DISPLAY 0.680851 (50 -300);
PAINT MONO (50 -300);
DISPLAY INVISIBLE (50 -300);
FORCEPROP 0 LAST CDS_SEC 1
J 0
(50 -300);
DISPLAY 1.021277 (50 -300);
DISPLAY INVISIBLE (50 -300);
FORCEPROP 1 LASTPIN (100 -350) $PN 1
J 0
(90 -335);
DISPLAY 0.787234 (90 -335);
PAINT MONO (90 -335);
FORCEPROP 1 LASTPIN (300 -350) $PN 2
J 0
(285 -335);
DISPLAY 0.787234 (285 -335);
PAINT MONO (285 -335);
FORCEPROP 1 LAST MATERIAL EMPTY
J 0
(225 -450);
DISPLAY 0.638298 (225 -450);
PAINT RED (225 -450);
FORCEPROP 1 LAST VALUE 0.1UF
J 2
(200 -450);
DISPLAY 0.638298 (200 -450);
FORCEPROP 2 LAST CDS_LIB pure_quanta
J 0
(200 -350);
DISPLAY INVISIBLE (200 -350);
FORCEPROP 1 LAST PACK_TYPE 0402
J 1
(200 -550);
DISPLAY 0.978723 (200 -550);
DISPLAY INVISIBLE (200 -550);
FORCEPROP 1 LAST TOLERANCE 10%
J 2
(200 -500);
DISPLAY 0.978723 (200 -500);
DISPLAY INVISIBLE (200 -500);
FORCEPROP 1 LAST VOLTAGE 25V
J 0
(200 -450);
DISPLAY 0.978723 (200 -450);
DISPLAY INVISIBLE (200 -450);
FORCEPROP 1 LAST PATH I455
J 0
(200 -150);
DISPLAY 0.978723 (200 -150);
PAINT WHITE (200 -150);
DISPLAY INVISIBLE (200 -150);
FORCEPROP 1 LAST PART_NUMBER CH4104K1B00
J 1
(200 -300);
DISPLAY 0.978723 (200 -300);
DISPLAY INVISIBLE (200 -300);
FORCEADD Q_CAP..2
(200 -500);
FORCEPROP 1 LAST LOCATION C67
J 1
(50 -500);
DISPLAY 0.638298 (50 -500);
FORCEPROP 0 LAST $SEC 1
J 0
(50 -450);
DISPLAY 0.680851 (50 -450);
PAINT MONO (50 -450);
DISPLAY INVISIBLE (50 -450);
FORCEPROP 0 LAST CDS_SEC 1
J 0
(50 -450);
DISPLAY 1.021277 (50 -450);
DISPLAY INVISIBLE (50 -450);
FORCEPROP 1 LASTPIN (100 -500) $PN 1
J 0
(90 -485);
DISPLAY 0.787234 (90 -485);
PAINT MONO (90 -485);
FORCEPROP 1 LASTPIN (300 -500) $PN 2
J 0
(285 -485);
DISPLAY 0.787234 (285 -485);
PAINT MONO (285 -485);
FORCEPROP 1 LAST MATERIAL EMPTY
J 0
(225 -600);
DISPLAY 0.638298 (225 -600);
PAINT RED (225 -600);
FORCEPROP 1 LAST VALUE 0.1UF
J 2
(200 -600);
DISPLAY 0.638298 (200 -600);
FORCEPROP 2 LAST CDS_LIB pure_quanta
J 0
(200 -500);
DISPLAY INVISIBLE (200 -500);
FORCEPROP 1 LAST PACK_TYPE 0402
J 1
(200 -700);
DISPLAY 0.978723 (200 -700);
DISPLAY INVISIBLE (200 -700);
FORCEPROP 1 LAST TOLERANCE 10%
J 2
(200 -650);
DISPLAY 0.978723 (200 -650);
DISPLAY INVISIBLE (200 -650);
FORCEPROP 1 LAST VOLTAGE 25V
J 0
(200 -600);
DISPLAY 0.978723 (200 -600);
DISPLAY INVISIBLE (200 -600);
FORCEPROP 1 LAST PATH I456
J 0
(200 -300);
DISPLAY 0.978723 (200 -300);
PAINT WHITE (200 -300);
DISPLAY INVISIBLE (200 -300);
FORCEPROP 1 LAST PART_NUMBER CH4104K1B00
J 1
(200 -450);
DISPLAY 0.978723 (200 -450);
DISPLAY INVISIBLE (200 -450);
FORCEADD OFFPAGE..5
(-1050 100);
FORCEPROP 2 LAST $XR0 241 
J 0
(-1305 100);
DISPLAY 0.638298 (-1305 100);
PAINT MONO (-1305 100);
FORCEPROP 2 LAST CDS_LIB standard
J 2
(-1050 100);
DISPLAY INVISIBLE (-1050 100);
FORCEPROP 1 LAST OFFPAGE TRUE
J 0
(-725 -25);
DISPLAY 0.872340 (-725 -25);
DISPLAY INVISIBLE (-725 -25);
FORCEPROP 1 LAST COMMENT_BODY TRUE
J 0
(-950 25);
DISPLAY 0.872340 (-950 25);
PAINT GREEN (-950 25);
DISPLAY INVISIBLE (-950 25);
FORCEPROP 2 LAST PATH I457
J 2
(-1225 175);
DISPLAY 1.021277 (-1225 175);
DISPLAY INVISIBLE (-1225 175);
FORCEADD OFFPAGE..5
(-1050 -50);
FORCEPROP 2 LAST $XR0 241 
J 0
(-1305 -50);
DISPLAY 0.638298 (-1305 -50);
PAINT MONO (-1305 -50);
FORCEPROP 2 LAST CDS_LIB standard
J 0
(-1050 -50);
DISPLAY INVISIBLE (-1050 -50);
FORCEPROP 1 LAST OFFPAGE TRUE
J 0
(-725 -175);
DISPLAY 0.872340 (-725 -175);
DISPLAY INVISIBLE (-725 -175);
FORCEPROP 1 LAST COMMENT_BODY TRUE
J 0
(-950 -125);
DISPLAY 0.872340 (-950 -125);
PAINT GREEN (-950 -125);
DISPLAY INVISIBLE (-950 -125);
FORCEPROP 2 LAST PATH I458
J 0
(-1000 25);
DISPLAY 1.021277 (-1000 25);
DISPLAY INVISIBLE (-1000 25);
FORCEADD OFFPAGE..5
(-1050 -200);
FORCEPROP 2 LAST $XR0 241 
J 0
(-1305 -200);
DISPLAY 0.638298 (-1305 -200);
PAINT MONO (-1305 -200);
FORCEPROP 2 LAST CDS_LIB standard
J 0
(-1050 -200);
DISPLAY INVISIBLE (-1050 -200);
FORCEPROP 1 LAST OFFPAGE TRUE
J 0
(-725 -325);
DISPLAY 0.872340 (-725 -325);
DISPLAY INVISIBLE (-725 -325);
FORCEPROP 1 LAST COMMENT_BODY TRUE
J 0
(-950 -275);
DISPLAY 0.872340 (-950 -275);
PAINT GREEN (-950 -275);
DISPLAY INVISIBLE (-950 -275);
FORCEPROP 2 LAST PATH I459
J 0
(-1000 -125);
DISPLAY 1.021277 (-1000 -125);
DISPLAY INVISIBLE (-1000 -125);
FORCEADD OFFPAGE..5
(-1050 -350);
FORCEPROP 2 LAST $XR0 241 
J 0
(-1305 -350);
DISPLAY 0.638298 (-1305 -350);
PAINT MONO (-1305 -350);
FORCEPROP 2 LAST CDS_LIB standard
J 0
(-1050 -350);
DISPLAY INVISIBLE (-1050 -350);
FORCEPROP 1 LAST OFFPAGE TRUE
J 0
(-725 -475);
DISPLAY 0.872340 (-725 -475);
DISPLAY INVISIBLE (-725 -475);
FORCEPROP 1 LAST COMMENT_BODY TRUE
J 0
(-950 -425);
DISPLAY 0.872340 (-950 -425);
PAINT GREEN (-950 -425);
DISPLAY INVISIBLE (-950 -425);
FORCEPROP 2 LAST PATH I460
J 0
(-1000 -275);
DISPLAY 1.021277 (-1000 -275);
DISPLAY INVISIBLE (-1000 -275);
FORCEADD OFFPAGE..5
(-1050 -500);
FORCEPROP 2 LAST $XR0 241 
J 0
(-1305 -500);
DISPLAY 0.638298 (-1305 -500);
PAINT MONO (-1305 -500);
FORCEPROP 2 LAST CDS_LIB standard
J 0
(-1050 -500);
DISPLAY INVISIBLE (-1050 -500);
FORCEPROP 1 LAST OFFPAGE TRUE
J 0
(-725 -625);
DISPLAY 0.872340 (-725 -625);
DISPLAY INVISIBLE (-725 -625);
FORCEPROP 1 LAST COMMENT_BODY TRUE
J 0
(-950 -575);
DISPLAY 0.872340 (-950 -575);
PAINT GREEN (-950 -575);
DISPLAY INVISIBLE (-950 -575);
FORCEPROP 2 LAST PATH I461
J 0
(-1000 -425);
DISPLAY 1.021277 (-1000 -425);
DISPLAY INVISIBLE (-1000 -425);
FORCEADD UNIVERSAL_GND..1
(650 -875);
FORCEPROP 3 LASTPIN (650 -825) SIG_NAME GND\g
J 0
(660 -815);
DISPLAY 0.659574 (660 -815);
PAINT MONO (660 -815);
DISPLAY INVISIBLE (660 -815);
FORCEPROP 2 LAST CDS_LIB pure_quanta_power
J 0
(650 -875);
DISPLAY INVISIBLE (650 -875);
FORCEPROP 1 LAST HDL_POWER GND
J 1
(675 -950);
DISPLAY 0.872340 (675 -950);
PAINT GREEN (675 -950);
DISPLAY INVISIBLE (675 -950);
FORCEPROP 1 LAST PATH I462
J 0
(725 -875);
DISPLAY 0.872340 (725 -875);
PAINT AQUA (725 -875);
DISPLAY INVISIBLE (725 -875);
FORCEADD Q_RES..1
(-4650 -3350);
FORCEPROP 1 LAST LOCATION R3113
J 0
(-4850 -3350);
DISPLAY 0.638298 (-4850 -3350);
FORCEPROP 0 LAST $SEC 1
J 0
(-4850 -3300);
DISPLAY 0.680851 (-4850 -3300);
PAINT MONO (-4850 -3300);
DISPLAY INVISIBLE (-4850 -3300);
FORCEPROP 0 LAST CDS_SEC 1
J 0
(-4850 -3300);
DISPLAY 1.021277 (-4850 -3300);
DISPLAY INVISIBLE (-4850 -3300);
FORCEPROP 1 LASTPIN (-4750 -3350) $PN 1
J 0
(-4738 -3338);
DISPLAY 0.787234 (-4738 -3338);
PAINT MONO (-4738 -3338);
FORCEPROP 1 LASTPIN (-4550 -3350) $PN 2
J 0
(-4588 -3338);
DISPLAY 0.787234 (-4588 -3338);
PAINT MONO (-4588 -3338);
FORCEPROP 1 LAST VALUE 33.2
J 2
(-4450 -3350);
DISPLAY 0.510638 (-4450 -3350);
FORCEPROP 1 LAST TOLERANCE 1%
J 0
(-4425 -3350);
DISPLAY 0.510638 (-4425 -3350);
FORCEPROP 1 LAST MATERIAL CHIP
J 0
(-4350 -3350);
DISPLAY 0.510638 (-4350 -3350);
FORCEPROP 1 LAST WATTAGE 1/16W
J 2
(-4550 -3250);
DISPLAY 0.404255 (-4550 -3250);
DISPLAY INVISIBLE (-4550 -3250);
FORCEPROP 1 LAST PACK_TYPE 0402LF
J 0
(-4775 -3250);
DISPLAY 0.404255 (-4775 -3250);
DISPLAY INVISIBLE (-4775 -3250);
FORCEPROP 2 LAST CDS_LIB pure_quanta
J 0
(-4650 -3350);
DISPLAY INVISIBLE (-4650 -3350);
FORCEPROP 1 LAST PATH I463
J 0
(-4700 -3200);
DISPLAY 0.978723 (-4700 -3200);
PAINT WHITE (-4700 -3200);
DISPLAY INVISIBLE (-4700 -3200);
FORCEPROP 1 LAST PART_NUMBER CS03322FB03
J 0
(-4775 -3300);
DISPLAY 0.404255 (-4775 -3300);
DISPLAY INVISIBLE (-4775 -3300);
FORCEADD Q_RES..1
(-4650 -3450);
FORCEPROP 1 LAST LOCATION R3114
J 0
(-4850 -3450);
DISPLAY 0.638298 (-4850 -3450);
FORCEPROP 0 LAST $SEC 1
J 0
(-4850 -3400);
DISPLAY 0.680851 (-4850 -3400);
PAINT MONO (-4850 -3400);
DISPLAY INVISIBLE (-4850 -3400);
FORCEPROP 0 LAST CDS_SEC 1
J 0
(-4850 -3400);
DISPLAY 1.021277 (-4850 -3400);
DISPLAY INVISIBLE (-4850 -3400);
FORCEPROP 1 LASTPIN (-4750 -3450) $PN 1
J 0
(-4738 -3438);
DISPLAY 0.787234 (-4738 -3438);
PAINT MONO (-4738 -3438);
FORCEPROP 1 LASTPIN (-4550 -3450) $PN 2
J 0
(-4588 -3438);
DISPLAY 0.787234 (-4588 -3438);
PAINT MONO (-4588 -3438);
FORCEPROP 1 LAST TOLERANCE 1%
J 0
(-4425 -3450);
DISPLAY 0.510638 (-4425 -3450);
FORCEPROP 1 LAST MATERIAL CHIP
J 0
(-4350 -3450);
DISPLAY 0.510638 (-4350 -3450);
FORCEPROP 1 LAST VALUE 33.2
J 2
(-4450 -3450);
DISPLAY 0.510638 (-4450 -3450);
FORCEPROP 1 LAST WATTAGE 1/16W
J 2
(-4550 -3350);
DISPLAY 0.404255 (-4550 -3350);
DISPLAY INVISIBLE (-4550 -3350);
FORCEPROP 1 LAST PACK_TYPE 0402LF
J 0
(-4775 -3350);
DISPLAY 0.404255 (-4775 -3350);
DISPLAY INVISIBLE (-4775 -3350);
FORCEPROP 2 LAST CDS_LIB pure_quanta
J 0
(-4650 -3450);
DISPLAY INVISIBLE (-4650 -3450);
FORCEPROP 1 LAST PATH I464
J 0
(-4700 -3300);
DISPLAY 0.978723 (-4700 -3300);
PAINT WHITE (-4700 -3300);
DISPLAY INVISIBLE (-4700 -3300);
FORCEPROP 1 LAST PART_NUMBER CS03322FB03
J 0
(-4775 -3400);
DISPLAY 0.404255 (-4775 -3400);
DISPLAY INVISIBLE (-4775 -3400);
FORCEADD OFFPAGE..5
R 2
(-875 725);
FORCEPROP 2 LAST $XR0 242 
J 0
(-686 725);
DISPLAY 0.638298 (-686 725);
PAINT MONO (-686 725);
FORCEPROP 2 LAST CDS_LIB standard
J 0
(-875 725);
DISPLAY INVISIBLE (-875 725);
FORCEPROP 1 LAST OFFPAGE TRUE
J 2
(-1200 600);
DISPLAY 0.872340 (-1200 600);
DISPLAY INVISIBLE (-1200 600);
FORCEPROP 1 LAST COMMENT_BODY TRUE
J 2
(-975 650);
DISPLAY 0.872340 (-975 650);
PAINT GREEN (-975 650);
DISPLAY INVISIBLE (-975 650);
FORCEPROP 2 LAST PATH I465
J 0
(-700 800);
DISPLAY 1.021277 (-700 800);
DISPLAY INVISIBLE (-700 800);
FORCEADD CONN60_101062636003K02LF..1
(-3750 -75);
FORCEPROP 1 LAST LOCATION J45
J 0
(-4000 1125);
DISPLAY 0.723404 (-4000 1125);
PAINT GREEN (-4000 1125);
FORCEPROP 2 LAST SEC 1
J 0
(-3975 1350);
DISPLAY 0.680851 (-3975 1350);
PAINT MONO (-3975 1350);
DISPLAY INVISIBLE (-3975 1350);
FORCEPROP 2 LASTPIN (-4150 825) $PN A1
J 2
(-4160 835);
DISPLAY 0.680851 (-4160 835);
PAINT MONO (-4160 835);
FORCEPROP 2 LASTPIN (-4150 775) $PN A2
J 2
(-4160 785);
DISPLAY 0.680851 (-4160 785);
PAINT MONO (-4160 785);
FORCEPROP 2 LASTPIN (-4150 725) $PN A3
J 2
(-4160 735);
DISPLAY 0.680851 (-4160 735);
PAINT MONO (-4160 735);
FORCEPROP 2 LASTPIN (-4150 675) $PN B1
J 2
(-4160 685);
DISPLAY 0.680851 (-4160 685);
PAINT MONO (-4160 685);
FORCEPROP 2 LASTPIN (-4150 625) $PN B2
J 2
(-4160 635);
DISPLAY 0.680851 (-4160 635);
PAINT MONO (-4160 635);
FORCEPROP 2 LASTPIN (-4150 575) $PN B3
J 2
(-4160 585);
DISPLAY 0.680851 (-4160 585);
PAINT MONO (-4160 585);
FORCEPROP 2 LASTPIN (-3350 825) $PN C1
J 0
(-3340 835);
DISPLAY 0.680851 (-3340 835);
PAINT MONO (-3340 835);
FORCEPROP 2 LASTPIN (-3350 775) $PN C2
J 0
(-3340 785);
DISPLAY 0.680851 (-3340 785);
PAINT MONO (-3340 785);
FORCEPROP 2 LASTPIN (-3350 725) $PN C3
J 0
(-3340 735);
DISPLAY 0.680851 (-3340 735);
PAINT MONO (-3340 735);
FORCEPROP 2 LASTPIN (-3350 675) $PN D1
J 0
(-3340 685);
DISPLAY 0.680851 (-3340 685);
PAINT MONO (-3340 685);
FORCEPROP 2 LASTPIN (-3350 625) $PN D2
J 0
(-3340 635);
DISPLAY 0.680851 (-3340 635);
PAINT MONO (-3340 635);
FORCEPROP 2 LASTPIN (-3350 575) $PN D3
J 0
(-3340 585);
DISPLAY 0.680851 (-3340 585);
PAINT MONO (-3340 585);
FORCEPROP 2 LASTPIN (-4150 425) $PN P1_1
J 2
(-4160 435);
DISPLAY 0.680851 (-4160 435);
PAINT MONO (-4160 435);
FORCEPROP 2 LASTPIN (-4150 375) $PN P1_2
J 2
(-4160 385);
DISPLAY 0.680851 (-4160 385);
PAINT MONO (-4160 385);
FORCEPROP 2 LASTPIN (-4150 325) $PN P1_3
J 2
(-4160 335);
DISPLAY 0.680851 (-4160 335);
PAINT MONO (-4160 335);
FORCEPROP 2 LASTPIN (-4150 275) $PN P1_4
J 2
(-4160 285);
DISPLAY 0.680851 (-4160 285);
PAINT MONO (-4160 285);
FORCEPROP 2 LASTPIN (-4150 225) $PN P1_5
J 2
(-4160 235);
DISPLAY 0.680851 (-4160 235);
PAINT MONO (-4160 235);
FORCEPROP 2 LASTPIN (-4150 175) $PN P1_6
J 2
(-4160 185);
DISPLAY 0.680851 (-4160 185);
PAINT MONO (-4160 185);
FORCEPROP 2 LASTPIN (-4150 125) $PN P1_7
J 2
(-4160 135);
DISPLAY 0.680851 (-4160 135);
PAINT MONO (-4160 135);
FORCEPROP 2 LASTPIN (-4150 75) $PN P1_8
J 2
(-4160 85);
DISPLAY 0.680851 (-4160 85);
PAINT MONO (-4160 85);
FORCEPROP 2 LASTPIN (-4150 -75) $PN P2_1
J 2
(-4160 -65);
DISPLAY 0.680851 (-4160 -65);
PAINT MONO (-4160 -65);
FORCEPROP 2 LASTPIN (-4150 -125) $PN P2_2
J 2
(-4160 -115);
DISPLAY 0.680851 (-4160 -115);
PAINT MONO (-4160 -115);
FORCEPROP 2 LASTPIN (-4150 -175) $PN P2_3
J 2
(-4160 -165);
DISPLAY 0.680851 (-4160 -165);
PAINT MONO (-4160 -165);
FORCEPROP 2 LASTPIN (-4150 -225) $PN P2_4
J 2
(-4160 -215);
DISPLAY 0.680851 (-4160 -215);
PAINT MONO (-4160 -215);
FORCEPROP 2 LASTPIN (-4150 -275) $PN P2_5
J 2
(-4160 -265);
DISPLAY 0.680851 (-4160 -265);
PAINT MONO (-4160 -265);
FORCEPROP 2 LASTPIN (-4150 -325) $PN P2_6
J 2
(-4160 -315);
DISPLAY 0.680851 (-4160 -315);
PAINT MONO (-4160 -315);
FORCEPROP 2 LASTPIN (-4150 -375) $PN P2_7
J 2
(-4160 -365);
DISPLAY 0.680851 (-4160 -365);
PAINT MONO (-4160 -365);
FORCEPROP 2 LASTPIN (-4150 -425) $PN P2_8
J 2
(-4160 -415);
DISPLAY 0.680851 (-4160 -415);
PAINT MONO (-4160 -415);
FORCEPROP 2 LASTPIN (-4150 -575) $PN P3_1
J 2
(-4160 -565);
DISPLAY 0.680851 (-4160 -565);
PAINT MONO (-4160 -565);
FORCEPROP 2 LASTPIN (-4150 -625) $PN P3_2
J 2
(-4160 -615);
DISPLAY 0.680851 (-4160 -615);
PAINT MONO (-4160 -615);
FORCEPROP 2 LASTPIN (-4150 -675) $PN P3_3
J 2
(-4160 -665);
DISPLAY 0.680851 (-4160 -665);
PAINT MONO (-4160 -665);
FORCEPROP 2 LASTPIN (-4150 -725) $PN P3_4
J 2
(-4160 -715);
DISPLAY 0.680851 (-4160 -715);
PAINT MONO (-4160 -715);
FORCEPROP 2 LASTPIN (-4150 -775) $PN P3_5
J 2
(-4160 -765);
DISPLAY 0.680851 (-4160 -765);
PAINT MONO (-4160 -765);
FORCEPROP 2 LASTPIN (-4150 -825) $PN P3_6
J 2
(-4160 -815);
DISPLAY 0.680851 (-4160 -815);
PAINT MONO (-4160 -815);
FORCEPROP 2 LASTPIN (-4150 -875) $PN P3_7
J 2
(-4160 -865);
DISPLAY 0.680851 (-4160 -865);
PAINT MONO (-4160 -865);
FORCEPROP 2 LASTPIN (-4150 -925) $PN P3_8
J 2
(-4160 -915);
DISPLAY 0.680851 (-4160 -915);
PAINT MONO (-4160 -915);
FORCEPROP 2 LASTPIN (-3350 425) $PN P4_1
J 0
(-3340 435);
DISPLAY 0.680851 (-3340 435);
PAINT MONO (-3340 435);
FORCEPROP 2 LASTPIN (-3350 375) $PN P4_2
J 0
(-3340 385);
DISPLAY 0.680851 (-3340 385);
PAINT MONO (-3340 385);
FORCEPROP 2 LASTPIN (-3350 325) $PN P4_3
J 0
(-3340 335);
DISPLAY 0.680851 (-3340 335);
PAINT MONO (-3340 335);
FORCEPROP 2 LASTPIN (-3350 275) $PN P4_4
J 0
(-3340 285);
DISPLAY 0.680851 (-3340 285);
PAINT MONO (-3340 285);
FORCEPROP 2 LASTPIN (-3350 225) $PN P4_5
J 0
(-3340 235);
DISPLAY 0.680851 (-3340 235);
PAINT MONO (-3340 235);
FORCEPROP 2 LASTPIN (-3350 175) $PN P4_6
J 0
(-3340 185);
DISPLAY 0.680851 (-3340 185);
PAINT MONO (-3340 185);
FORCEPROP 2 LASTPIN (-3350 125) $PN P4_7
J 0
(-3340 135);
DISPLAY 0.680851 (-3340 135);
PAINT MONO (-3340 135);
FORCEPROP 2 LASTPIN (-3350 75) $PN P4_8
J 0
(-3340 85);
DISPLAY 0.680851 (-3340 85);
PAINT MONO (-3340 85);
FORCEPROP 2 LASTPIN (-3350 -75) $PN P5_1
J 0
(-3340 -65);
DISPLAY 0.680851 (-3340 -65);
PAINT MONO (-3340 -65);
FORCEPROP 2 LASTPIN (-3350 -125) $PN P5_2
J 0
(-3340 -115);
DISPLAY 0.680851 (-3340 -115);
PAINT MONO (-3340 -115);
FORCEPROP 2 LASTPIN (-3350 -175) $PN P5_3
J 0
(-3340 -165);
DISPLAY 0.680851 (-3340 -165);
PAINT MONO (-3340 -165);
FORCEPROP 2 LASTPIN (-3350 -225) $PN P5_4
J 0
(-3340 -215);
DISPLAY 0.680851 (-3340 -215);
PAINT MONO (-3340 -215);
FORCEPROP 2 LASTPIN (-3350 -275) $PN P5_5
J 0
(-3340 -265);
DISPLAY 0.680851 (-3340 -265);
PAINT MONO (-3340 -265);
FORCEPROP 2 LASTPIN (-3350 -325) $PN P5_6
J 0
(-3340 -315);
DISPLAY 0.680851 (-3340 -315);
PAINT MONO (-3340 -315);
FORCEPROP 2 LASTPIN (-3350 -375) $PN P5_7
J 0
(-3340 -365);
DISPLAY 0.680851 (-3340 -365);
PAINT MONO (-3340 -365);
FORCEPROP 2 LASTPIN (-3350 -425) $PN P5_8
J 0
(-3340 -415);
DISPLAY 0.680851 (-3340 -415);
PAINT MONO (-3340 -415);
FORCEPROP 2 LASTPIN (-3350 -575) $PN P6_1
J 0
(-3340 -565);
DISPLAY 0.680851 (-3340 -565);
PAINT MONO (-3340 -565);
FORCEPROP 2 LASTPIN (-3350 -625) $PN P6_2
J 0
(-3340 -615);
DISPLAY 0.680851 (-3340 -615);
PAINT MONO (-3340 -615);
FORCEPROP 2 LASTPIN (-3350 -675) $PN P6_3
J 0
(-3340 -665);
DISPLAY 0.680851 (-3340 -665);
PAINT MONO (-3340 -665);
FORCEPROP 2 LASTPIN (-3350 -725) $PN P6_4
J 0
(-3340 -715);
DISPLAY 0.680851 (-3340 -715);
PAINT MONO (-3340 -715);
FORCEPROP 2 LASTPIN (-3350 -775) $PN P6_5
J 0
(-3340 -765);
DISPLAY 0.680851 (-3340 -765);
PAINT MONO (-3340 -765);
FORCEPROP 2 LASTPIN (-3350 -825) $PN P6_6
J 0
(-3340 -815);
DISPLAY 0.680851 (-3340 -815);
PAINT MONO (-3340 -815);
FORCEPROP 2 LASTPIN (-3350 -875) $PN P6_7
J 0
(-3340 -865);
DISPLAY 0.680851 (-3340 -865);
PAINT MONO (-3340 -865);
FORCEPROP 2 LASTPIN (-3350 -925) $PN P6_8
J 0
(-3340 -915);
DISPLAY 0.680851 (-3340 -915);
PAINT MONO (-3340 -915);
FORCEPROP 2 LAST VALUE CONN60_10106263-6003K02LF
J 0
(-4000 1175);
DISPLAY 0.680851 (-4000 1175);
FORCEPROP 2 LAST PART_TYPE THLF
J 0
(-4000 1225);
DISPLAY 0.680851 (-4000 1225);
FORCEPROP 1 LAST MATERIAL IO
J 0
(-3997 942);
DISPLAY 0.723404 (-3997 942);
PAINT GREEN (-3997 942);
FORCEPROP 1 LAST CDS_LMAN_SYM_OUTLINE -250,1000,250,-1000
J 0
(-3750 -75);
DISPLAY 0.468085 (-3750 -75);
PAINT GREEN (-3750 -75);
DISPLAY INVISIBLE (-3750 -75);
FORCEPROP 1 LAST NEEDS_NO_SIZE TRUE
J 0
(-3750 -75);
DISPLAY 0.723404 (-3750 -75);
PAINT GREEN (-3750 -75);
DISPLAY INVISIBLE (-3750 -75);
FORCEPROP 2 LAST CDS_LIB pure_quanta
J 0
(-3750 -75);
DISPLAY INVISIBLE (-3750 -75);
FORCEPROP 2 LAST SEC_TYPE 
J 0
(-3975 1350);
DISPLAY 0.680851 (-3975 1350);
DISPLAY INVISIBLE (-3975 1350);
FORCEPROP 1 LAST PATH I466
J 0
(-3750 -75);
DISPLAY 0.723404 (-3750 -75);
PAINT GREEN (-3750 -75);
DISPLAY INVISIBLE (-3750 -75);
FORCEPROP 1 LAST PART_NUMBER DFHD60MR024
J 0
(-3997 1069);
DISPLAY 0.723404 (-3997 1069);
PAINT GREEN (-3997 1069);
DISPLAY INVISIBLE (-3997 1069);
FORCEADD Q_RES..1
(-5750 775);
FORCEPROP 1 LAST LOCATION R8102
J 0
(-5950 775);
DISPLAY 0.638298 (-5950 775);
FORCEPROP 0 LAST $SEC 1
J 0
(-5950 825);
DISPLAY 0.680851 (-5950 825);
PAINT MONO (-5950 825);
DISPLAY INVISIBLE (-5950 825);
FORCEPROP 0 LAST CDS_SEC 1
J 0
(-5950 825);
DISPLAY 0.680851 (-5950 825);
DISPLAY INVISIBLE (-5950 825);
FORCEPROP 1 LASTPIN (-5850 775) $PN 1
J 0
(-5838 787);
DISPLAY 0.787234 (-5838 787);
PAINT MONO (-5838 787);
FORCEPROP 1 LASTPIN (-5650 775) $PN 2
J 0
(-5688 787);
DISPLAY 0.787234 (-5688 787);
PAINT MONO (-5688 787);
FORCEPROP 1 LAST VALUE 0
J 2
(-5575 775);
DISPLAY 0.404255 (-5575 775);
FORCEPROP 1 LAST TOLERANCE 5%
J 0
(-5525 775);
DISPLAY 0.404255 (-5525 775);
FORCEPROP 1 LAST MATERIAL CHIP
J 0
(-5450 775);
DISPLAY 0.404255 (-5450 775);
FORCEPROP 1 LAST PACK_TYPE 0402LF
J 0
(-5500 775);
DISPLAY 0.638298 (-5500 775);
DISPLAY INVISIBLE (-5500 775);
FORCEPROP 1 LAST WATTAGE 1/16W
J 2
(-5775 625);
DISPLAY 0.978723 (-5775 625);
DISPLAY INVISIBLE (-5775 625);
FORCEPROP 2 LAST CDS_LIB pure_quanta
J 0
(-5750 775);
DISPLAY INVISIBLE (-5750 775);
FORCEPROP 1 LAST PATH I467
J 0
(-5800 925);
DISPLAY 0.978723 (-5800 925);
PAINT WHITE (-5800 925);
DISPLAY INVISIBLE (-5800 925);
FORCEPROP 1 LAST PART_NUMBER CS00002JB13
J 0
(-5875 625);
DISPLAY 0.510638 (-5875 625);
DISPLAY INVISIBLE (-5875 625);
FORCEADD OFFPAGE..1
(-7050 775);
FORCEPROP 2 LAST $XR1 243 
J 0
(-7452 775);
DISPLAY 0.638298 (-7452 775);
PAINT MONO (-7452 775);
FORCEPROP 2 LAST $XR0 150 
J 0
(-7332 775);
DISPLAY 0.638298 (-7332 775);
PAINT MONO (-7332 775);
FORCEPROP 2 LAST CDS_LIB standard
J 0
(-7050 775);
DISPLAY INVISIBLE (-7050 775);
FORCEPROP 1 LAST OFFPAGE TRUE
J 0
(-6725 650);
DISPLAY 0.872340 (-6725 650);
DISPLAY INVISIBLE (-6725 650);
FORCEPROP 1 LAST COMMENT_BODY TRUE
J 0
(-6925 675);
DISPLAY 0.872340 (-6925 675);
PAINT GREEN (-6925 675);
DISPLAY INVISIBLE (-6925 675);
FORCEPROP 2 LAST PATH I468
J 0
(-7000 850);
DISPLAY 0.680851 (-7000 850);
DISPLAY INVISIBLE (-7000 850);
FORCEADD Q_CAP..2
(200 -700);
FORCEPROP 1 LAST LOCATION C8011
J 1
(50 -700);
DISPLAY 0.638298 (50 -700);
FORCEPROP 0 LAST $SEC 1
J 0
(50 -650);
DISPLAY 0.680851 (50 -650);
PAINT MONO (50 -650);
DISPLAY INVISIBLE (50 -650);
FORCEPROP 0 LAST CDS_SEC 1
J 0
(50 -650);
DISPLAY 0.680851 (50 -650);
DISPLAY INVISIBLE (50 -650);
FORCEPROP 1 LASTPIN (100 -700) $PN 1
J 0
(90 -685);
DISPLAY 0.787234 (90 -685);
PAINT MONO (90 -685);
FORCEPROP 1 LASTPIN (300 -700) $PN 2
J 0
(285 -685);
DISPLAY 0.787234 (285 -685);
PAINT MONO (285 -685);
FORCEPROP 1 LAST MATERIAL EMPTY
J 0
(225 -800);
DISPLAY 0.638298 (225 -800);
PAINT RED (225 -800);
FORCEPROP 1 LAST VALUE 0.1UF
J 2
(200 -800);
DISPLAY 0.638298 (200 -800);
FORCEPROP 2 LAST CDS_LIB pure_quanta
J 0
(200 -700);
DISPLAY INVISIBLE (200 -700);
FORCEPROP 1 LAST VOLTAGE 25V
J 0
(200 -800);
DISPLAY 0.978723 (200 -800);
DISPLAY INVISIBLE (200 -800);
FORCEPROP 1 LAST TOLERANCE 10%
J 2
(200 -850);
DISPLAY 0.978723 (200 -850);
DISPLAY INVISIBLE (200 -850);
FORCEPROP 1 LAST PACK_TYPE 0402
J 1
(200 -900);
DISPLAY 0.978723 (200 -900);
DISPLAY INVISIBLE (200 -900);
FORCEPROP 1 LAST PATH I469
J 0
(200 -500);
DISPLAY 0.978723 (200 -500);
PAINT WHITE (200 -500);
DISPLAY INVISIBLE (200 -500);
FORCEPROP 1 LAST PART_NUMBER CH4104K1B00
J 1
(200 -650);
DISPLAY 0.978723 (200 -650);
DISPLAY INVISIBLE (200 -650);
FORCEADD OFFPAGE..5
(-1050 -700);
FORCEPROP 2 LAST $XR0 241 
J 0
(-1305 -700);
DISPLAY 0.638298 (-1305 -700);
PAINT MONO (-1305 -700);
FORCEPROP 2 LAST CDS_LIB standard
J 0
(-1050 -700);
DISPLAY INVISIBLE (-1050 -700);
FORCEPROP 1 LAST OFFPAGE TRUE
J 0
(-725 -825);
DISPLAY 0.872340 (-725 -825);
DISPLAY INVISIBLE (-725 -825);
FORCEPROP 1 LAST COMMENT_BODY TRUE
J 0
(-950 -775);
DISPLAY 0.872340 (-950 -775);
PAINT GREEN (-950 -775);
DISPLAY INVISIBLE (-950 -775);
FORCEPROP 2 LAST PATH I470
J 0
(-1000 -625);
DISPLAY 0.680851 (-1000 -625);
DISPLAY INVISIBLE (-1000 -625);
FORCEADD UNIVERSAL_POWER..1
(-1100 1325);
FORCEPROP 3 LASTPIN (-1100 1275) SIG_NAME P3V3_AUX\g
J 0
(-1090 1285);
DISPLAY 0.659574 (-1090 1285);
PAINT MONO (-1090 1285);
DISPLAY INVISIBLE (-1090 1285);
FORCEPROP 1 LAST HDL_POWER P3V3_AUX
J 1
(-1100 1375);
DISPLAY 0.872340 (-1100 1375);
PAINT GREEN (-1100 1375);
FORCEPROP 2 LAST CDS_LIB pure_quanta_power
J 0
(-1100 1325);
DISPLAY INVISIBLE (-1100 1325);
FORCEPROP 1 LAST PATH I471
J 0
(-1050 1350);
DISPLAY 0.872340 (-1050 1350);
PAINT AQUA (-1050 1350);
DISPLAY INVISIBLE (-1050 1350);
FORCEADD Q_RES..2
(-1100 1050);
FORCEPROP 1 LAST LOCATION R9000
J 0
(-1050 1225);
DISPLAY 0.787234 (-1050 1225);
FORCEPROP 0 LAST $SEC 1
J 0
(-1050 1275);
DISPLAY 0.680851 (-1050 1275);
PAINT MONO (-1050 1275);
DISPLAY INVISIBLE (-1050 1275);
FORCEPROP 0 LAST CDS_SEC 1
J 0
(-1050 1275);
DISPLAY 0.680851 (-1050 1275);
DISPLAY INVISIBLE (-1050 1275);
FORCEPROP 1 LASTPIN (-1100 1150) $PN 1
J 0
(-1095 1112);
DISPLAY 0.787234 (-1095 1112);
PAINT MONO (-1095 1112);
FORCEPROP 1 LASTPIN (-1100 950) $PN 2
J 0
(-1095 960);
DISPLAY 0.787234 (-1095 960);
PAINT MONO (-1095 960);
FORCEPROP 1 LAST MATERIAL CHIP
J 0
(-1055 1025);
DISPLAY 0.638298 (-1055 1025);
FORCEPROP 1 LAST WATTAGE 1/16W
J 0
(-1055 1075);
DISPLAY 0.638298 (-1055 1075);
FORCEPROP 1 LAST PACK_TYPE 0402LF
J 0
(-1055 925);
DISPLAY 0.638298 (-1055 925);
FORCEPROP 1 LAST TOLERANCE 1%
J 0
(-1050 1125);
DISPLAY 0.638298 (-1050 1125);
FORCEPROP 1 LAST VALUE 1K
J 0
(-1050 1175);
DISPLAY 0.638298 (-1050 1175);
FORCEPROP 2 LAST CDS_LIB pure_quanta
J 0
(-1100 1050);
DISPLAY INVISIBLE (-1100 1050);
FORCEPROP 1 LAST PATH I472
J 0
(-1050 1225);
DISPLAY 0.978723 (-1050 1225);
PAINT WHITE (-1050 1225);
DISPLAY INVISIBLE (-1050 1225);
FORCEPROP 1 LAST PART_NUMBER CS21002FB06
J 0
(-1055 975);
DISPLAY 0.638298 (-1055 975);
DISPLAY INVISIBLE (-1055 975);
FORCEADD UNIVERSAL_POWER..1
(-6275 -2050);
FORCEPROP 3 LASTPIN (-6275 -2100) SIG_NAME P3V3_AUX\g
J 0
(-6265 -2090);
DISPLAY 0.659574 (-6265 -2090);
PAINT MONO (-6265 -2090);
DISPLAY INVISIBLE (-6265 -2090);
FORCEPROP 1 LAST HDL_POWER P3V3_AUX
J 1
(-6275 -2000);
DISPLAY 0.872340 (-6275 -2000);
PAINT GREEN (-6275 -2000);
FORCEPROP 2 LAST CDS_LIB pure_quanta_power
J 0
(-6275 -2050);
DISPLAY INVISIBLE (-6275 -2050);
FORCEPROP 1 LAST PATH I473
J 0
(-6225 -2025);
DISPLAY 0.872340 (-6225 -2025);
PAINT AQUA (-6225 -2025);
DISPLAY INVISIBLE (-6225 -2025);
FORCEADD Q_RES..2
R 2
(-6275 -2325);
FORCEPROP 1 LAST LOCATION R2950
J 2
(-6325 -2150);
DISPLAY 0.787234 (-6325 -2150);
FORCEPROP 0 LAST $SEC 1
J 0
(-6325 -2100);
DISPLAY 0.680851 (-6325 -2100);
PAINT MONO (-6325 -2100);
DISPLAY INVISIBLE (-6325 -2100);
FORCEPROP 0 LAST CDS_SEC 1
J 0
(-6325 -2100);
DISPLAY 0.680851 (-6325 -2100);
DISPLAY INVISIBLE (-6325 -2100);
FORCEPROP 1 LASTPIN (-6275 -2225) $PN 1
J 2
(-6280 -2263);
DISPLAY 0.787234 (-6280 -2263);
PAINT MONO (-6280 -2263);
FORCEPROP 1 LASTPIN (-6275 -2425) $PN 2
J 2
(-6280 -2415);
DISPLAY 0.787234 (-6280 -2415);
PAINT MONO (-6280 -2415);
FORCEPROP 1 LAST PACK_TYPE 0402LF
J 2
(-6320 -2450);
DISPLAY 0.638298 (-6320 -2450);
FORCEPROP 1 LAST MATERIAL CHIP
J 2
(-6320 -2350);
DISPLAY 0.638298 (-6320 -2350);
FORCEPROP 1 LAST WATTAGE 1/16W
J 2
(-6320 -2300);
DISPLAY 0.638298 (-6320 -2300);
FORCEPROP 1 LAST TOLERANCE 1%
J 2
(-6325 -2250);
DISPLAY 0.638298 (-6325 -2250);
FORCEPROP 1 LAST VALUE 1K
J 2
(-6325 -2200);
DISPLAY 0.638298 (-6325 -2200);
FORCEPROP 2 LAST CDS_LIB pure_quanta
J 2
(-6275 -2325);
DISPLAY INVISIBLE (-6275 -2325);
FORCEPROP 1 LAST PATH I475
J 2
(-6325 -2150);
DISPLAY 0.978723 (-6325 -2150);
PAINT WHITE (-6325 -2150);
DISPLAY INVISIBLE (-6325 -2150);
FORCEPROP 1 LAST PART_NUMBER CS21002FB06
J 2
(-6320 -2400);
DISPLAY 0.638298 (-6320 -2400);
DISPLAY INVISIBLE (-6320 -2400);
FORCEADD Q_RES..1
(-2150 575);
FORCEPROP 1 LAST LOCATION R1526
J 0
(-2375 575);
DISPLAY 0.638298 (-2375 575);
FORCEPROP 0 LAST $SEC 1
J 0
(-2375 625);
DISPLAY 0.680851 (-2375 625);
PAINT MONO (-2375 625);
DISPLAY INVISIBLE (-2375 625);
FORCEPROP 0 LAST CDS_SEC 1
J 0
(-2375 625);
DISPLAY 0.680851 (-2375 625);
DISPLAY INVISIBLE (-2375 625);
FORCEPROP 1 LASTPIN (-2250 575) $PN 1
J 0
(-2238 587);
DISPLAY 0.787234 (-2238 587);
PAINT MONO (-2238 587);
FORCEPROP 1 LASTPIN (-2050 575) $PN 2
J 0
(-2088 587);
DISPLAY 0.787234 (-2088 587);
PAINT MONO (-2088 587);
FORCEPROP 1 LAST MATERIAL CHIP
J 0
(-1850 575);
DISPLAY 0.404255 (-1850 575);
FORCEPROP 1 LAST VALUE 0
J 2
(-1975 575);
DISPLAY 0.404255 (-1975 575);
FORCEPROP 1 LAST TOLERANCE 5%
J 0
(-1925 575);
DISPLAY 0.404255 (-1925 575);
FORCEPROP 1 LAST WATTAGE 1/16W
J 2
(-2175 425);
DISPLAY 0.978723 (-2175 425);
DISPLAY INVISIBLE (-2175 425);
FORCEPROP 1 LAST PACK_TYPE 0402LF
J 0
(-1900 575);
DISPLAY 0.638298 (-1900 575);
DISPLAY INVISIBLE (-1900 575);
FORCEPROP 2 LAST CDS_LIB pure_quanta
J 0
(-2150 575);
DISPLAY INVISIBLE (-2150 575);
FORCEPROP 1 LAST PATH I476
J 0
(-2200 725);
DISPLAY 0.978723 (-2200 725);
PAINT WHITE (-2200 725);
DISPLAY INVISIBLE (-2200 725);
FORCEPROP 1 LAST PART_NUMBER CS00002JB13
J 0
(-2275 425);
DISPLAY 0.510638 (-2275 425);
DISPLAY INVISIBLE (-2275 425);
FORCEADD OFFPAGE..5
R 2
(-850 575);
FORCEPROP 2 LAST $XR0 269 
J 0
(-661 575);
DISPLAY 0.638298 (-661 575);
PAINT MONO (-661 575);
FORCEPROP 2 LAST CDS_LIB standard
J 0
(-850 575);
DISPLAY INVISIBLE (-850 575);
FORCEPROP 1 LAST OFFPAGE TRUE
J 2
(-1175 450);
DISPLAY 0.872340 (-1175 450);
DISPLAY INVISIBLE (-1175 450);
FORCEPROP 1 LAST COMMENT_BODY TRUE
J 2
(-950 500);
DISPLAY 0.872340 (-950 500);
PAINT GREEN (-950 500);
DISPLAY INVISIBLE (-950 500);
FORCEPROP 2 LAST PATH I477
J 0
(-675 650);
DISPLAY 0.680851 (-675 650);
DISPLAY INVISIBLE (-675 650);
FORCEADD Q_CAP..1
R 2
(-1700 375);
FORCEPROP 1 LAST LOCATION C1115
J 2
(-1750 475);
DISPLAY 0.638298 (-1750 475);
FORCEPROP 0 LAST $SEC 1
J 0
(-1750 525);
DISPLAY 0.680851 (-1750 525);
PAINT MONO (-1750 525);
DISPLAY INVISIBLE (-1750 525);
FORCEPROP 0 LAST CDS_SEC 1
J 0
(-1750 525);
DISPLAY 0.680851 (-1750 525);
DISPLAY INVISIBLE (-1750 525);
FORCEPROP 1 LASTPIN (-1700 475) $PN 1
J 2
(-1710 455);
DISPLAY 0.787234 (-1710 455);
PAINT MONO (-1710 455);
FORCEPROP 1 LASTPIN (-1700 275) $PN 2
J 2
(-1710 255);
DISPLAY 0.787234 (-1710 255);
PAINT MONO (-1710 255);
FORCEPROP 1 LAST PACK_TYPE C0805
J 2
(-1750 175);
DISPLAY 0.638298 (-1750 175);
FORCEPROP 1 LAST VALUE 22UF
J 2
(-1750 425);
DISPLAY 0.638298 (-1750 425);
FORCEPROP 1 LAST VOLTAGE 16V
J 2
(-1750 375);
DISPLAY 0.638298 (-1750 375);
FORCEPROP 1 LAST TOLERANCE 20%
J 2
(-1750 325);
DISPLAY 0.638298 (-1750 325);
FORCEPROP 1 LAST MATERIAL EMPTY
J 2
(-1750 275);
DISPLAY 0.638298 (-1750 275);
PAINT RED (-1750 275);
FORCEPROP 2 LAST CDS_LIB pure_quanta
J 2
(-1700 375);
DISPLAY INVISIBLE (-1700 375);
FORCEPROP 1 LAST PATH I478
J 2
(-1750 525);
DISPLAY 0.978723 (-1750 525);
PAINT WHITE (-1750 525);
DISPLAY INVISIBLE (-1750 525);
FORCEPROP 1 LAST PART_NUMBER CH6223MEA00
J 2
(-1750 225);
DISPLAY 0.638298 (-1750 225);
DISPLAY INVISIBLE (-1750 225);
FORCEADD UNIVERSAL_GND..1
(-1700 50);
FORCEPROP 3 LASTPIN (-1700 100) SIG_NAME GND\g
J 0
(-1690 110);
DISPLAY 0.659574 (-1690 110);
PAINT MONO (-1690 110);
DISPLAY INVISIBLE (-1690 110);
FORCEPROP 2 LAST CDS_LIB pure_quanta_power
J 0
(-1700 50);
DISPLAY INVISIBLE (-1700 50);
FORCEPROP 1 LAST HDL_POWER GND
J 1
(-1675 -25);
DISPLAY 0.872340 (-1675 -25);
PAINT GREEN (-1675 -25);
DISPLAY INVISIBLE (-1675 -25);
FORCEPROP 1 LAST PATH I479
J 0
(-1625 50);
DISPLAY 0.872340 (-1625 50);
PAINT AQUA (-1625 50);
DISPLAY INVISIBLE (-1625 50);
FORCEADD DNS..2
(-1450 -2950);
PAINT RED (-1450 -2950);
FORCEPROP 2 LAST CDS_LIB mstr_misc
J 0
(-1450 -2950);
DISPLAY INVISIBLE (-1450 -2950);
FORCEPROP 1 LAST COMMENT_BODY TRUE
J 0
(-1450 -2950);
DISPLAY INVISIBLE (-1450 -2950);
FORCEADD DNS..2
(-1675 350);
PAINT RED (-1675 350);
FORCEPROP 2 LAST CDS_LIB mstr_misc
J 0
(-1675 350);
DISPLAY INVISIBLE (-1675 350);
FORCEPROP 1 LAST COMMENT_BODY TRUE
J 0
(-1675 350);
DISPLAY INVISIBLE (-1675 350);
FORCEADD QUANTA_TITLE_BLOCK_C..1
(1100 -4600);
FORCEPROP 0 LAST CDS_CON_LAST_MODIFIED Thu Sep 14 16:12:31 2023
J 0
(-785 -4585);
PAINT MONO (-785 -4585);
DISPLAY INVISIBLE (-785 -4585);
FORCEPROP 2 LAST CUSTOM_TXT_CDS <XR_PAGE_TITLE>
J 0
(-6790 650);
DISPLAY 0.638298 (-6790 650);
PAINT PINK (-6790 650);
DISPLAY INVISIBLE (-6790 650);
FORCEPROP 2 LAST CUSTOM_TXT_CDS <CON_LAST_MODIFIED>
J 0
(-785 -4585);
DISPLAY 0.978723 (-785 -4585);
FORCEPROP 2 LAST CUSTOM_TXT_CDS <Q_NUMBER>
J 0
(-303 -4497);
DISPLAY 1.212766 (-303 -4497);
FORCEPROP 2 LAST CUSTOM_TXT_CDS <CON_PAGE_NUM> OF <CON_TOTAL_PAGES>
J 0
(654 -4582);
DISPLAY 0.978723 (654 -4582);
FORCEPROP 2 LAST CUSTOM_TXT_CDS <Q_REV>
J 0
(916 -4497);
DISPLAY 1.212766 (916 -4497);
FORCEPROP 2 LAST CUSTOM_TXT_CDS <Q_PROJ>
J 0
(-1282 -4498);
DISPLAY 1.212766 (-1282 -4498);
FORCEPROP 2 LAST CUSTOM_TXT_CDS <NAME_1>
J 0
(-2075 -4425);
FORCEPROP 2 LAST CUSTOM_TXT_CDS <NAME_2>
J 0
(-2075 -4550);
FORCEPROP 1 LAST Q_TITLE POWER CONNECTOR/ISOLATED
J 0
(-8166 -4574);
DISPLAY 2.446809 (-8166 -4574);
PAINT GREEN (-8166 -4574);
FORCEPROP 2 LAST CDS_LIB pure_quanta
J 0
(1100 -4600);
PAINT MONO (1100 -4600);
DISPLAY INVISIBLE (1100 -4600);
FORCEPROP 1 LAST CDS_LMAN_SYM_OUTLINE -9475,6775,100,-125
J 0
(1100 -4600);
DISPLAY 0.468085 (1100 -4600);
PAINT GREEN (1100 -4600);
DISPLAY INVISIBLE (1100 -4600);
FORCEPROP 2 LAST PAGE_BORDER TRUE
J 0
(-6790 650);
DISPLAY 0.638298 (-6790 650);
PAINT PINK (-6790 650);
DISPLAY INVISIBLE (-6790 650);
FORCEPROP 2 LAST CDS_XR_PAGE_TITLE CR-241 : @T6G_MB_LIB.T6G(SCH_1):PAGE241
J 0
(-6790 650);
DISPLAY 0.638298 (-6790 650);
PAINT PINK (-6790 650);
DISPLAY INVISIBLE (-6790 650);
FORCEPROP 1 LAST Q_DEPT BU9
J 1
(-2663 -4551);
DISPLAY 1.957447 (-2663 -4551);
PAINT GREEN (-2663 -4551);
DISPLAY INVISIBLE (-2663 -4551);
FORCEPROP 1 LAST COMMENT_BODY TRUE
J 0
(1112 -4613);
DISPLAY 0.978723 (1112 -4613);
PAINT GREEN (1112 -4613);
DISPLAY INVISIBLE (1112 -4613);
FORCEADD DNS..2
(-1775 -2925);
PAINT RED (-1775 -2925);
FORCEPROP 2 LAST CDS_LIB mstr_misc
J 0
(-1775 -2925);
DISPLAY INVISIBLE (-1775 -2925);
FORCEPROP 1 LAST COMMENT_BODY TRUE
J 0
(-1775 -2925);
DISPLAY INVISIBLE (-1775 -2925);
FORCEADD DNS..2
(225 -675);
PAINT RED (225 -675);
FORCEPROP 2 LAST CDS_LIB mstr_misc
J 0
(225 -675);
DISPLAY INVISIBLE (225 -675);
FORCEPROP 1 LAST COMMENT_BODY TRUE
J 0
(225 -675);
DISPLAY INVISIBLE (225 -675);
FORCEADD DNS..2
(225 -500);
PAINT RED (225 -500);
FORCEPROP 2 LAST CDS_LIB mstr_misc
J 0
(225 -500);
DISPLAY INVISIBLE (225 -500);
FORCEPROP 1 LAST COMMENT_BODY TRUE
J 0
(225 -500);
DISPLAY INVISIBLE (225 -500);
FORCEADD DNS..2
(225 -350);
PAINT RED (225 -350);
FORCEPROP 2 LAST CDS_LIB mstr_misc
J 0
(225 -350);
DISPLAY INVISIBLE (225 -350);
FORCEPROP 1 LAST COMMENT_BODY TRUE
J 0
(225 -350);
DISPLAY INVISIBLE (225 -350);
FORCEADD DNS..2
(225 -50);
PAINT RED (225 -50);
FORCEPROP 2 LAST CDS_LIB mstr_misc
J 0
(225 -50);
DISPLAY INVISIBLE (225 -50);
FORCEPROP 1 LAST COMMENT_BODY TRUE
J 0
(225 -50);
DISPLAY INVISIBLE (225 -50);
FORCEADD DNS..2
(225 100);
PAINT RED (225 100);
FORCEPROP 2 LAST CDS_LIB mstr_misc
J 0
(225 100);
DISPLAY INVISIBLE (225 100);
FORCEPROP 1 LAST COMMENT_BODY TRUE
J 0
(225 100);
DISPLAY INVISIBLE (225 100);
FORCEADD DNS..2
(-3125 -3850);
PAINT RED (-3125 -3850);
FORCEPROP 2 LAST CDS_LIB mstr_misc
J 0
(-3125 -3850);
DISPLAY INVISIBLE (-3125 -3850);
FORCEPROP 1 LAST COMMENT_BODY TRUE
J 0
(-3125 -3850);
DISPLAY INVISIBLE (-3125 -3850);
FORCEADD DNS..2
(225 -200);
PAINT RED (225 -200);
FORCEPROP 2 LAST CDS_LIB mstr_misc
J 0
(225 -200);
DISPLAY INVISIBLE (225 -200);
FORCEPROP 1 LAST COMMENT_BODY TRUE
J 0
(225 -200);
DISPLAY INVISIBLE (225 -200);
WIRE 16 -1 (-5975 -1825)(-5975 -1950);
WIRE 16 -1 (-5975 -2850)(-5975 -3050);
WIRE 16 -1 (-3500 -3550)(-3525 -3550);
WIRE 16 -1 (-3525 -3550)(-3525 -3600);
WIRE 16 -1 (-2250 -2925)(-2250 -3025);
WIRE 16 -1 (-1100 1275)(-1100 1150);
WIRE 16 -1 (-6275 -2100)(-6275 -2225);
WIRE 16 -1 (-1700 275)(-1700 100);
WIRE 16 -1 (100 -700)(-1000 -700);
FORCEPROP 2 LAST SIG_NAME FM_AC_PWR_BTN_PDB_N
J 0
(-760 -690);
DISPLAY 0.680851 (-760 -690);
WIRE 16 -1 (100 -350)(-1000 -350);
FORCEPROP 2 LAST SIG_NAME FM_FAN_PWR_EN_R
J 0
(-760 -340);
DISPLAY 0.638298 (-760 -340);
PAINT WHITE (-760 -340);
WIRE 16 -1 (300 -500)(650 -500);
WIRE 16 -1 (650 -350)(650 -500);
WIRE 16 -1 (650 -500)(650 -700);
WIRE 16 -1 (300 -700)(650 -700);
WIRE 16 -1 (650 -700)(650 -825);
WIRE 16 -1 (650 -200)(650 -350);
WIRE 16 -1 (300 -350)(650 -350);
WIRE 16 -1 (650 -50)(650 -200);
WIRE 16 -1 (300 -200)(650 -200);
WIRE 16 -1 (650 100)(650 -50);
WIRE 16 -1 (300 -50)(650 -50);
WIRE 16 -1 (300 100)(650 100);
WIRE 16 -1 (-1000 100)(100 100);
FORCEPROP 2 LAST SIG_NAME RST_SMB_SWITCH_R_N
J 0
(-760 110);
DISPLAY 0.638298 (-760 110);
PAINT WHITE (-760 110);
WIRE 16 -1 (100 -500)(-1000 -500);
FORCEPROP 2 LAST SIG_NAME FM_GPU_HSC_EN_BUF_R1
J 0
(-760 -490);
DISPLAY 0.638298 (-760 -490);
PAINT WHITE (-760 -490);
WIRE 16 -1 (-3350 -925)(-3125 -925);
WIRE 16 -1 (-3125 -925)(-3125 -875);
WIRE 16 -1 (-3125 -875)(-3125 -825);
WIRE 16 -1 (-3125 -875)(-3350 -875);
WIRE 16 -1 (-3125 -825)(-3125 -775);
WIRE 16 -1 (-3350 -825)(-3125 -825);
WIRE 16 -1 (-3125 -775)(-3125 -725);
WIRE 16 -1 (-3125 -775)(-3350 -775);
WIRE 16 -1 (-3125 -725)(-3125 -675);
WIRE 16 -1 (-3350 -725)(-3125 -725);
WIRE 16 -1 (-3125 -675)(-3125 -625);
WIRE 16 -1 (-3125 -675)(-3350 -675);
WIRE 16 -1 (-3125 -625)(-3125 -575);
WIRE 16 -1 (-3350 -625)(-3125 -625);
WIRE 16 -1 (-3125 -575)(-3125 -425);
WIRE 16 -1 (-3125 -575)(-3350 -575);
WIRE 16 -1 (-3125 -425)(-3125 -375);
WIRE 16 -1 (-3350 -425)(-3125 -425);
WIRE 16 -1 (-3125 -375)(-3125 -325);
WIRE 16 -1 (-3125 -375)(-3350 -375);
WIRE 16 -1 (-3125 -325)(-3125 -275);
WIRE 16 -1 (-3350 -325)(-3125 -325);
WIRE 16 -1 (-3125 -275)(-3125 -225);
WIRE 16 -1 (-3125 -275)(-3350 -275);
WIRE 16 -1 (-3125 -225)(-3125 -175);
WIRE 16 -1 (-3350 -225)(-3125 -225);
WIRE 16 -1 (-3125 -175)(-3125 -125);
WIRE 16 -1 (-3125 -175)(-3350 -175);
WIRE 16 -1 (-3125 -125)(-3125 -75);
WIRE 16 -1 (-3350 -125)(-3125 -125);
WIRE 16 -1 (-3125 -75)(-3125 75);
WIRE 16 -1 (-3125 -75)(-3350 -75);
WIRE 16 -1 (-3125 75)(-3125 125);
WIRE 16 -1 (-3350 75)(-3125 75);
WIRE 16 -1 (-3125 125)(-3125 175);
WIRE 16 -1 (-3125 125)(-3350 125);
WIRE 16 -1 (-3125 175)(-3125 225);
WIRE 16 -1 (-3350 175)(-3125 175);
WIRE 16 -1 (-3125 225)(-3125 275);
WIRE 16 -1 (-3125 225)(-3350 225);
WIRE 16 -1 (-3125 275)(-3125 325);
WIRE 16 -1 (-3350 275)(-3125 275);
WIRE 16 -1 (-3125 325)(-3125 375);
WIRE 16 -1 (-3125 325)(-3350 325);
WIRE 16 -1 (-3125 375)(-3125 425);
WIRE 16 -1 (-3350 375)(-3125 375);
WIRE 16 -1 (-2875 425)(-3125 425);
WIRE 16 -1 (-3125 425)(-3350 425);
WIRE 16 -1 (-4150 -875)(-4375 -875);
WIRE 16 -1 (-4375 -825)(-4375 -875);
WIRE 16 -1 (-4375 -875)(-4375 -925);
WIRE 16 -1 (-4375 -925)(-4150 -925);
WIRE 16 -1 (-4375 -925)(-4375 -1150);
WIRE 16 -1 (-4375 -825)(-4150 -825);
WIRE 16 -1 (-4375 -775)(-4375 -825);
WIRE 16 -1 (-4150 -775)(-4375 -775);
WIRE 16 -1 (-4375 -725)(-4375 -775);
WIRE 16 -1 (-4375 -725)(-4150 -725);
WIRE 16 -1 (-4375 -675)(-4375 -725);
WIRE 16 -1 (-4150 -675)(-4375 -675);
WIRE 16 -1 (-4375 -625)(-4375 -675);
WIRE 16 -1 (-4375 -625)(-4150 -625);
WIRE 16 -1 (-4375 -575)(-4375 -625);
WIRE 16 -1 (-4375 -425)(-4375 -575);
WIRE 16 -1 (-4150 -575)(-4375 -575);
WIRE 16 -1 (-4375 -425)(-4150 -425);
WIRE 16 -1 (-4375 -375)(-4375 -425);
WIRE 16 -1 (-4150 -375)(-4375 -375);
WIRE 16 -1 (-4375 -325)(-4375 -375);
WIRE 16 -1 (-4375 -325)(-4150 -325);
WIRE 16 -1 (-4375 -275)(-4375 -325);
WIRE 16 -1 (-4150 -275)(-4375 -275);
WIRE 16 -1 (-4375 -225)(-4375 -275);
WIRE 16 -1 (-4375 -225)(-4150 -225);
WIRE 16 -1 (-4375 -175)(-4375 -225);
WIRE 16 -1 (-4150 -175)(-4375 -175);
WIRE 16 -1 (-4375 -125)(-4375 -175);
WIRE 16 -1 (-4375 -125)(-4150 -125);
WIRE 16 -1 (-4375 -75)(-4375 -125);
WIRE 16 -1 (-4375 75)(-4375 -75);
WIRE 16 -1 (-4150 -75)(-4375 -75);
WIRE 16 -1 (-4375 75)(-4150 75);
WIRE 16 -1 (-4375 125)(-4375 75);
WIRE 16 -1 (-4150 125)(-4375 125);
WIRE 16 -1 (-4375 175)(-4375 125);
WIRE 16 -1 (-4375 175)(-4150 175);
WIRE 16 -1 (-4375 225)(-4375 175);
WIRE 16 -1 (-4150 225)(-4375 225);
WIRE 16 -1 (-4375 275)(-4375 225);
WIRE 16 -1 (-4375 275)(-4150 275);
WIRE 16 -1 (-4375 325)(-4375 275);
WIRE 16 -1 (-4150 325)(-4375 325);
WIRE 16 -1 (-4375 375)(-4375 325);
WIRE 16 -1 (-4375 375)(-4150 375);
WIRE 16 -1 (-4375 425)(-4375 375);
WIRE 16 -1 (-4375 575)(-4375 425);
WIRE 16 -1 (-4150 425)(-4375 425);
WIRE 16 -1 (-4150 575)(-4375 575);
WIRE 16 -1 (-950 825)(-3350 825);
FORCEPROP 2 LAST SIG_NAME SMB_FAN_3V3AUX_BUF_R_SCL
J 0
(-3110 835);
DISPLAY 0.638298 (-3110 835);
PAINT WHITE (-3110 835);
WIRE 16 -1 (-1700 575)(-900 575);
FORCEPROP 2 LAST SIG_NAME PDB_PRSNT_R_N
J 0
(-1610 585);
DISPLAY 0.680851 (-1610 585);
WIRE 16 -1 (-1700 575)(-1700 475);
WIRE 16 -1 (-2050 575)(-1700 575);
WIRE 16 -1 (-2050 625)(-925 625);
FORCEPROP 2 LAST SIG_NAME FM_GPU_HSC_EN_BUF
J 0
(-1635 635);
DISPLAY 0.638298 (-1635 635);
PAINT WHITE (-1635 635);
WIRE 16 -1 (-2250 725)(-3350 725);
FORCEPROP 2 LAST SIG_NAME HPDB_HSC_PWRGD_R
J 0
(-3110 735);
DISPLAY 0.638298 (-3110 735);
PAINT WHITE (-3110 735);
FORCEPROP 2 LASTPROP $XR0 241 
J 0
(-3236 735);
DISPLAY 0.638298 (-3236 735);
PAINT MONO (-3236 735);
WIRE 16 -1 (-3350 575)(-2250 575);
FORCEPROP 2 LAST SIG_NAME PDB_PRSNT_N
J 0
(-3110 585);
DISPLAY 0.638298 (-3110 585);
PAINT WHITE (-3110 585);
FORCEPROP 2 LASTPROP $XR0 241 
J 0
(-3236 585);
DISPLAY 0.638298 (-3236 585);
PAINT MONO (-3236 585);
WIRE 16 -1 (-2050 675)(-1100 675);
FORCEPROP 2 LAST SIG_NAME FM_FAN_PWR_EN
J 0
(-1635 685);
DISPLAY 0.638298 (-1635 685);
PAINT WHITE (-1635 685);
WIRE 16 -1 (-1100 675)(-925 675);
WIRE 16 -1 (-1100 950)(-1100 675);
WIRE 16 -1 (-950 775)(-3350 775);
FORCEPROP 2 LAST SIG_NAME SMB_FAN_3V3AUX_BUF_R_SDA
J 0
(-3110 785);
DISPLAY 0.638298 (-3110 785);
PAINT WHITE (-3110 785);
WIRE 16 -1 (-2050 725)(-925 725);
FORCEPROP 2 LAST SIG_NAME HPDB_HSC_PWRGD
J 0
(-1635 735);
DISPLAY 0.638298 (-1635 735);
PAINT WHITE (-1635 735);
WIRE 16 -1 (-1000 -50)(100 -50);
FORCEPROP 2 LAST SIG_NAME PDB_PRSNT_N
J 0
(-760 -40);
DISPLAY 0.638298 (-760 -40);
PAINT WHITE (-760 -40);
WIRE 16 -1 (100 -200)(-1000 -200);
FORCEPROP 2 LAST SIG_NAME HPDB_HSC_PWRGD_R
J 0
(-760 -190);
DISPLAY 0.638298 (-760 -190);
PAINT WHITE (-760 -190);
WIRE 16 -1 (-2250 625)(-3350 625);
FORCEPROP 2 LAST SIG_NAME FM_GPU_HSC_EN_BUF_R1
J 0
(-3110 635);
DISPLAY 0.638298 (-3110 635);
PAINT WHITE (-3110 635);
FORCEPROP 2 LASTPROP $XR0 241 
J 0
(-3236 635);
DISPLAY 0.638298 (-3236 635);
PAINT MONO (-3236 635);
WIRE 16 -1 (-2250 675)(-3350 675);
FORCEPROP 2 LAST SIG_NAME FM_FAN_PWR_EN_R
J 0
(-3110 685);
DISPLAY 0.638298 (-3110 685);
PAINT WHITE (-3110 685);
FORCEPROP 2 LASTPROP $XR0 241 
J 0
(-3236 685);
DISPLAY 0.638298 (-3236 685);
PAINT MONO (-3236 685);
WIRE 16 -1 (-5850 775)(-7000 775);
FORCEPROP 2 LAST SIG_NAME FM_AC_PWR_BTN_R_N
J 0
(-6785 785);
DISPLAY 0.680851 (-6785 785);
WIRE 16 -1 (-4750 -3250)(-5400 -3250);
WIRE 16 -1 (-5400 -2375)(-5400 -3250);
WIRE 16 -1 (-5400 -2375)(-5100 -2375);
WIRE 16 -1 (-5975 -2375)(-5400 -2375);
FORCEPROP 2 LAST SIG_NAME FM_PDB_BUF_EN_R1
J 0
(-5885 -2365);
DISPLAY 0.638298 (-5885 -2365);
PAINT WHITE (-5885 -2365);
WIRE 16 -1 (-5975 -2150)(-5975 -2375);
WIRE 16 -1 (-5975 -2375)(-5975 -2450);
WIRE 16 -1 (-6275 -2425)(-6275 -2650);
WIRE 16 -1 (-6275 -2650)(-6175 -2650);
WIRE 16 -1 (-6775 -2650)(-6275 -2650);
FORCEPROP 2 LAST SIG_NAME FM_PDB_BUF_EN_R1_N
J 0
(-6710 -2650);
DISPLAY 0.404255 (-6710 -2650);
PAINT WHITE (-6710 -2650);
FORCEPROP 2 LASTPROP $XRERR UNIQUE?
J 0
(-6950 -2650);
DISPLAY 0.638298 (-6950 -2650);
PAINT MONO (-6950 -2650);
DISPLAY INVISIBLE (-6950 -2650);
WIRE 16 -1 (-7800 -2650)(-6975 -2650);
FORCEPROP 2 LAST SIG_NAME FM_PDB_BUF_EN_R_N
J 0
(-7735 -2640);
DISPLAY 0.638298 (-7735 -2640);
PAINT WHITE (-7735 -2640);
WIRE 16 -1 (-4150 775)(-5650 775);
FORCEPROP 2 LAST SIG_NAME FM_AC_PWR_BTN_PDB_N
J 0
(-5260 785);
DISPLAY 0.680851 (-5260 785);
FORCEPROP 2 LASTPROP $XR0 241 
J 0
(-5356 785);
DISPLAY 0.638298 (-5356 785);
PAINT MONO (-5356 785);
WIRE 16 -1 (-4150 625)(-7000 625);
FORCEPROP 2 LAST SIG_NAME PWRGD_P3V3_AUX_PDB_BUF
J 0
(-6685 635);
DISPLAY 0.638298 (-6685 635);
PAINT WHITE (-6685 635);
WIRE 16 -1 (-4150 725)(-7000 725);
FORCEPROP 2 LAST SIG_NAME P3V3_PDB_AUX_ADC
J 0
(-6685 735);
DISPLAY 0.638298 (-6685 735);
PAINT WHITE (-6685 735);
WIRE 16 -1 (-4150 825)(-4775 825);
FORCEPROP 2 LAST SIG_NAME TP_J45_A1
J 0
(-4685 835);
DISPLAY 0.680851 (-4685 835);
FORCEPROP 2 LASTPROP $XRERR UNIQUE?
J 0
(-5015 825);
DISPLAY 0.638298 (-5015 825);
PAINT MONO (-5015 825);
DISPLAY INVISIBLE (-5015 825);
WIRE 16 -1 (-5650 675)(-4150 675);
FORCEPROP 2 LAST SIG_NAME RST_SMB_SWITCH_R_N
J 0
(-5129 675);
DISPLAY 0.638298 (-5129 675);
PAINT WHITE (-5129 675);
FORCEPROP 2 LASTPROP $XR0 241 
J 0
(-5399 675);
DISPLAY 0.638298 (-5399 675);
PAINT MONO (-5399 675);
WIRE 16 -1 (-5850 675)(-7000 675);
FORCEPROP 2 LAST SIG_NAME RST_SMB_SWITCH_N
J 0
(-6685 685);
DISPLAY 0.638298 (-6685 685);
PAINT WHITE (-6685 685);
WIRE 16 -1 (425 -3450)(-975 -3450);
FORCEPROP 2 LAST SIG_NAME SMB_FAN_3V3AUX_BUF_R_SDA
J 0
(-635 -3440);
DISPLAY 0.638298 (-635 -3440);
PAINT WHITE (-635 -3440);
WIRE 16 -1 (425 -3350)(-975 -3350);
FORCEPROP 2 LAST SIG_NAME SMB_FAN_3V3AUX_BUF_R_SCL
J 0
(-635 -3340);
DISPLAY 0.638298 (-635 -3340);
PAINT WHITE (-635 -3340);
WIRE 16 -1 (-3225 -3875)(-3750 -3875);
WIRE 16 -1 (-3750 -3875)(-3750 -3450);
WIRE 16 -1 (-3750 -3450)(-3500 -3450);
WIRE 16 -1 (-4550 -3450)(-3750 -3450);
FORCEPROP 2 LAST SIG_NAME SMB_FAN_3V3AUX_R_SDA
J 0
(-4235 -3440);
DISPLAY 0.638298 (-4235 -3440);
PAINT WHITE (-4235 -3440);
FORCEPROP 2 LASTPROP $XRERR UNIQUE?
J 0
(-4475 -3440);
DISPLAY 0.638298 (-4475 -3440);
PAINT MONO (-4475 -3440);
DISPLAY INVISIBLE (-4475 -3440);
WIRE 16 -1 (-5450 -3350)(-4750 -3350);
FORCEPROP 2 LAST SIG_NAME SMB_FAN_3V3AUX_SCL
J 0
(-5385 -3340);
DISPLAY 0.638298 (-5385 -3340);
PAINT WHITE (-5385 -3340);
WIRE 16 -1 (-5450 -3450)(-4750 -3450);
FORCEPROP 2 LAST SIG_NAME SMB_FAN_3V3AUX_SDA
J 0
(-5385 -3440);
DISPLAY 0.638298 (-5385 -3440);
PAINT WHITE (-5385 -3440);
WIRE 16 -1 (-3625 -3800)(-3225 -3800);
WIRE 16 -1 (-3625 -3800)(-3625 -3350);
WIRE 16 -1 (-3625 -3350)(-3500 -3350);
WIRE 16 -1 (-4550 -3350)(-3625 -3350);
FORCEPROP 2 LAST SIG_NAME SMB_FAN_3V3AUX_R_SCL
J 0
(-4235 -3340);
DISPLAY 0.638298 (-4235 -3340);
PAINT WHITE (-4235 -3340);
FORCEPROP 2 LASTPROP $XRERR UNIQUE?
J 0
(-4475 -3340);
DISPLAY 0.638298 (-4475 -3340);
PAINT MONO (-4475 -3340);
DISPLAY INVISIBLE (-4475 -3340);
WIRE 16 -1 (-3500 -3250)(-4550 -3250);
FORCEPROP 2 LAST SIG_NAME MB_PDB_SMB9_R_EN
J 0
(-4235 -3240);
DISPLAY 0.638298 (-4235 -3240);
PAINT WHITE (-4235 -3240);
FORCEPROP 2 LASTPROP $XRERR UNIQUE?
J 0
(-4475 -3240);
DISPLAY 0.638298 (-4475 -3240);
PAINT MONO (-4475 -3240);
DISPLAY INVISIBLE (-4475 -3240);
WIRE 16 -1 (-1800 -3000)(-1800 -3350);
WIRE 16 -1 (-1800 -3350)(-1175 -3350);
WIRE 16 -1 (-2625 -3350)(-1800 -3350);
FORCEPROP 2 LAST SIG_NAME SMB_FAN_3V3AUX_BUF_SCL
J 0
(-2485 -3340);
DISPLAY 0.638298 (-2485 -3340);
PAINT WHITE (-2485 -3340);
FORCEPROP 2 LASTPROP $XRERR UNIQUE?
J 0
(-2725 -3340);
DISPLAY 0.638298 (-2725 -3340);
PAINT MONO (-2725 -3340);
DISPLAY INVISIBLE (-2725 -3340);
WIRE 16 -1 (-2700 -3350)(-2625 -3350);
WIRE 16 -1 (-2625 -3800)(-2625 -3350);
WIRE 16 -1 (-3025 -3800)(-2625 -3800);
WIRE 16 -1 (-1550 -3025)(-1550 -3450);
WIRE 16 -1 (-1550 -3450)(-1175 -3450);
WIRE 16 -1 (-2500 -3450)(-1550 -3450);
WIRE 16 -1 (-2500 -3875)(-2500 -3450);
WIRE 16 -1 (-2700 -3450)(-2500 -3450);
FORCEPROP 2 LAST SIG_NAME SMB_FAN_3V3AUX_BUF_SDA
J 0
(-2485 -3440);
DISPLAY 0.638298 (-2485 -3440);
PAINT WHITE (-2485 -3440);
FORCEPROP 2 LASTPROP $XRERR UNIQUE?
J 0
(-2725 -3440);
DISPLAY 0.638298 (-2725 -3440);
PAINT MONO (-2725 -3440);
DISPLAY INVISIBLE (-2725 -3440);
WIRE 16 -1 (-2500 -3875)(-3025 -3875);
WIRE 16 -1 (-1550 -2825)(-1550 -2700);
WIRE 16 -1 (-1800 -2700)(-1550 -2700);
WIRE 16 -1 (-1800 -2800)(-1800 -2700);
WIRE 16 -1 (-1800 -2700)(-1800 -2650);
WIRE 16 -1 (-2700 -3250)(-2600 -3250);
WIRE 16 -1 (-2600 -3250)(-2600 -2650);
WIRE 16 -1 (-2600 -2650)(-2250 -2650);
WIRE 16 -1 (-2600 -2650)(-2600 -2600);
WIRE 16 -1 (-2250 -2650)(-2250 -2725);
DOT 1 (-6275 -2650);
DOT 1 (-3125 -375);
DOT 1 (650 -700);
DOT 1 (650 -500);
DOT 1 (-4375 275);
DOT 1 (-3125 -675);
DOT 1 (-4375 -325);
DOT 1 (-4375 -425);
DOT 1 (-4375 -925);
DOT 1 (-4375 -875);
DOT 1 (-3125 -425);
DOT 1 (-3125 75);
DOT 1 (-4375 175);
DOT 1 (-3125 -825);
DOT 1 (-3125 -125);
DOT 1 (-4375 425);
DOT 1 (-3125 425);
DOT 1 (-4375 -575);
DOT 1 (-3125 -575);
DOT 1 (-4375 -75);
DOT 1 (-3125 -75);
DOT 1 (-4375 375);
DOT 1 (-4375 325);
DOT 1 (-4375 225);
DOT 1 (-3125 -725);
DOT 1 (-3125 -175);
DOT 1 (-4375 125);
DOT 1 (-3125 125);
DOT 1 (-3125 175);
DOT 1 (-4375 -825);
DOT 1 (-3125 -325);
DOT 1 (650 -200);
DOT 1 (650 -350);
DOT 1 (650 -50);
DOT 1 (-3125 225);
DOT 1 (-3125 325);
DOT 1 (-4375 75);
DOT 1 (-3750 -3450);
DOT 1 (-3125 -775);
DOT 1 (-3125 375);
DOT 1 (-3125 -275);
DOT 1 (-2625 -3350);
DOT 1 (-2500 -3450);
DOT 1 (-3625 -3350);
DOT 1 (-4375 -775);
DOT 1 (-3125 -625);
DOT 1 (-4375 -675);
DOT 1 (-4375 -625);
DOT 1 (-1550 -3450);
DOT 1 (-1800 -3350);
DOT 1 (-4375 -725);
DOT 1 (-4375 -275);
DOT 1 (-2600 -2650);
DOT 1 (-4375 -125);
DOT 1 (-4375 -225);
DOT 1 (-3125 275);
DOT 1 (-4375 -375);
DOT 1 (-4375 -175);
DOT 1 (-1800 -2700);
DOT 1 (-3125 -875);
DOT 1 (-3125 -225);
DOT 1 (-1100 675);
DOT 1 (-5975 -2375);
DOT 1 (-5400 -2375);
DOT 1 (-1700 575);
QUIT
